FILE_TYPE = MACRO_DRAWING;
SET COLOR_WIRE YELLOW;
SET COLOR_PROP ORANGE;
SET COLOR_DOT WHITE;
SET COLOR_ARC YELLOW;
SET COLOR_BODY GREEN;
SET COLOR_NOTE PURPLE;
SET PROP_DISPLAY VALUE;
SET PAGE_NUMBER P81;
FORCEADD LCMXO3LF9400C5BG484C..6
(-6800 1600);
FORCEPROP 1 LAST LOCATION U18
J 0
(-7047 3239);
DISPLAY 0.723404 (-7047 3239);
PAINT GREEN (-7047 3239);
FORCEPROP 2 LAST SEC 6
J 0
(-7025 3275);
DISPLAY 0.680851 (-7025 3275);
PAINT MONO (-7025 3275);
DISPLAY INVISIBLE (-7025 3275);
FORCEPROP 2 LASTPIN (-6400 2900) $PN A1
J 0
(-6390 2910);
DISPLAY 0.680851 (-6390 2910);
PAINT MONO (-6390 2910);
FORCEPROP 2 LASTPIN (-6400 2850) $PN A22
J 0
(-6390 2860);
DISPLAY 0.680851 (-6390 2860);
PAINT MONO (-6390 2860);
FORCEPROP 2 LASTPIN (-6400 2800) $PN B7
J 0
(-6390 2810);
DISPLAY 0.680851 (-6390 2810);
PAINT MONO (-6390 2810);
FORCEPROP 2 LASTPIN (-6400 2750) $PN B16
J 0
(-6390 2760);
DISPLAY 0.680851 (-6390 2760);
PAINT MONO (-6390 2760);
FORCEPROP 2 LASTPIN (-6400 2700) $PN C2
J 0
(-6390 2710);
DISPLAY 0.680851 (-6390 2710);
PAINT MONO (-6390 2710);
FORCEPROP 2 LASTPIN (-6400 2650) $PN C11
J 0
(-6390 2660);
DISPLAY 0.680851 (-6390 2660);
PAINT MONO (-6390 2660);
FORCEPROP 2 LASTPIN (-6400 2600) $PN E5
J 0
(-6390 2610);
DISPLAY 0.680851 (-6390 2610);
PAINT MONO (-6390 2610);
FORCEPROP 2 LASTPIN (-6400 2550) $PN E18
J 0
(-6390 2560);
DISPLAY 0.680851 (-6390 2560);
PAINT MONO (-6390 2560);
FORCEPROP 2 LASTPIN (-6400 2500) $PN F2
J 0
(-6390 2510);
DISPLAY 0.680851 (-6390 2510);
PAINT MONO (-6390 2510);
FORCEPROP 2 LASTPIN (-6400 2450) $PN F21
J 0
(-6390 2460);
DISPLAY 0.680851 (-6390 2460);
PAINT MONO (-6390 2460);
FORCEPROP 2 LASTPIN (-6400 2400) $PN H8
J 0
(-6390 2410);
DISPLAY 0.680851 (-6390 2410);
PAINT MONO (-6390 2410);
FORCEPROP 2 LASTPIN (-6400 2350) $PN H10
J 0
(-6390 2360);
DISPLAY 0.680851 (-6390 2360);
PAINT MONO (-6390 2360);
FORCEPROP 2 LASTPIN (-6400 2300) $PN H13
J 0
(-6390 2310);
DISPLAY 0.680851 (-6390 2310);
PAINT MONO (-6390 2310);
FORCEPROP 2 LASTPIN (-6400 2250) $PN H15
J 0
(-6390 2260);
DISPLAY 0.680851 (-6390 2260);
PAINT MONO (-6390 2260);
FORCEPROP 2 LASTPIN (-6400 2200) $PN J9
J 0
(-6390 2210);
DISPLAY 0.680851 (-6390 2210);
PAINT MONO (-6390 2210);
FORCEPROP 2 LASTPIN (-6400 2150) $PN J10
J 0
(-6390 2160);
DISPLAY 0.680851 (-6390 2160);
PAINT MONO (-6390 2160);
FORCEPROP 2 LASTPIN (-6400 2100) $PN J11
J 0
(-6390 2110);
DISPLAY 0.680851 (-6390 2110);
PAINT MONO (-6390 2110);
FORCEPROP 2 LASTPIN (-6400 2050) $PN J12
J 0
(-6390 2060);
DISPLAY 0.680851 (-6390 2060);
PAINT MONO (-6390 2060);
FORCEPROP 2 LASTPIN (-6400 2000) $PN J13
J 0
(-6390 2010);
DISPLAY 0.680851 (-6390 2010);
PAINT MONO (-6390 2010);
FORCEPROP 2 LASTPIN (-6400 1950) $PN J14
J 0
(-6390 1960);
DISPLAY 0.680851 (-6390 1960);
PAINT MONO (-6390 1960);
FORCEPROP 2 LASTPIN (-6400 1900) $PN K9
J 0
(-6390 1910);
DISPLAY 0.680851 (-6390 1910);
PAINT MONO (-6390 1910);
FORCEPROP 2 LASTPIN (-6400 1850) $PN K14
J 0
(-6390 1860);
DISPLAY 0.680851 (-6390 1860);
PAINT MONO (-6390 1860);
FORCEPROP 2 LASTPIN (-6400 1800) $PN K21
J 0
(-6390 1810);
DISPLAY 0.680851 (-6390 1810);
PAINT MONO (-6390 1810);
FORCEPROP 2 LASTPIN (-6400 1750) $PN L2
J 0
(-6390 1760);
DISPLAY 0.680851 (-6390 1760);
PAINT MONO (-6390 1760);
FORCEPROP 2 LASTPIN (-6400 1700) $PN L9
J 0
(-6390 1710);
DISPLAY 0.680851 (-6390 1710);
PAINT MONO (-6390 1710);
FORCEPROP 2 LASTPIN (-6400 1650) $PN L10
J 0
(-6390 1660);
DISPLAY 0.680851 (-6390 1660);
PAINT MONO (-6390 1660);
FORCEPROP 2 LASTPIN (-6400 1600) $PN L13
J 0
(-6390 1610);
DISPLAY 0.680851 (-6390 1610);
PAINT MONO (-6390 1610);
FORCEPROP 2 LASTPIN (-6400 1550) $PN L14
J 0
(-6390 1560);
DISPLAY 0.680851 (-6390 1560);
PAINT MONO (-6390 1560);
FORCEPROP 2 LASTPIN (-6400 1500) $PN L18
J 0
(-6390 1510);
DISPLAY 0.680851 (-6390 1510);
PAINT MONO (-6390 1510);
FORCEPROP 2 LASTPIN (-6400 1450) $PN M4
J 0
(-6390 1460);
DISPLAY 0.680851 (-6390 1460);
PAINT MONO (-6390 1460);
FORCEPROP 2 LASTPIN (-6400 1400) $PN M9
J 0
(-6390 1410);
DISPLAY 0.680851 (-6390 1410);
PAINT MONO (-6390 1410);
FORCEPROP 2 LASTPIN (-6400 1350) $PN M10
J 0
(-6390 1360);
DISPLAY 0.680851 (-6390 1360);
PAINT MONO (-6390 1360);
FORCEPROP 2 LASTPIN (-6400 1300) $PN M13
J 0
(-6390 1310);
DISPLAY 0.680851 (-6390 1310);
PAINT MONO (-6390 1310);
FORCEPROP 2 LASTPIN (-6400 1250) $PN M14
J 0
(-6390 1260);
DISPLAY 0.680851 (-6390 1260);
PAINT MONO (-6390 1260);
FORCEPROP 2 LASTPIN (-6400 1200) $PN N9
J 0
(-6390 1210);
DISPLAY 0.680851 (-6390 1210);
PAINT MONO (-6390 1210);
FORCEPROP 2 LASTPIN (-6400 1150) $PN N14
J 0
(-6390 1160);
DISPLAY 0.680851 (-6390 1160);
PAINT MONO (-6390 1160);
FORCEPROP 2 LASTPIN (-6400 1100) $PN N21
J 0
(-6390 1110);
DISPLAY 0.680851 (-6390 1110);
PAINT MONO (-6390 1110);
FORCEPROP 2 LASTPIN (-6400 1050) $PN P9
J 0
(-6390 1060);
DISPLAY 0.680851 (-6390 1060);
PAINT MONO (-6390 1060);
FORCEPROP 2 LASTPIN (-6400 1000) $PN P10
J 0
(-6390 1010);
DISPLAY 0.680851 (-6390 1010);
PAINT MONO (-6390 1010);
FORCEPROP 2 LASTPIN (-6400 950) $PN P11
J 0
(-6390 960);
DISPLAY 0.680851 (-6390 960);
PAINT MONO (-6390 960);
FORCEPROP 2 LASTPIN (-6400 900) $PN P12
J 0
(-6390 910);
DISPLAY 0.680851 (-6390 910);
PAINT MONO (-6390 910);
FORCEPROP 2 LASTPIN (-6400 850) $PN P13
J 0
(-6390 860);
DISPLAY 0.680851 (-6390 860);
PAINT MONO (-6390 860);
FORCEPROP 2 LASTPIN (-6400 800) $PN P14
J 0
(-6390 810);
DISPLAY 0.680851 (-6390 810);
PAINT MONO (-6390 810);
FORCEPROP 2 LASTPIN (-6400 750) $PN R8
J 0
(-6390 760);
DISPLAY 0.680851 (-6390 760);
PAINT MONO (-6390 760);
FORCEPROP 2 LASTPIN (-6400 700) $PN R15
J 0
(-6390 710);
DISPLAY 0.680851 (-6390 710);
PAINT MONO (-6390 710);
FORCEPROP 2 LASTPIN (-6400 650) $PN V2
J 0
(-6390 660);
DISPLAY 0.680851 (-6390 660);
PAINT MONO (-6390 660);
FORCEPROP 2 LASTPIN (-6400 600) $PN V21
J 0
(-6390 610);
DISPLAY 0.680851 (-6390 610);
PAINT MONO (-6390 610);
FORCEPROP 2 LASTPIN (-6400 550) $PN W12
J 0
(-6390 560);
DISPLAY 0.680851 (-6390 560);
PAINT MONO (-6390 560);
FORCEPROP 2 LASTPIN (-6400 500) $PN Y7
J 0
(-6390 510);
DISPLAY 0.680851 (-6390 510);
PAINT MONO (-6390 510);
FORCEPROP 2 LASTPIN (-6400 450) $PN Y16
J 0
(-6390 460);
DISPLAY 0.680851 (-6390 460);
PAINT MONO (-6390 460);
FORCEPROP 2 LASTPIN (-6400 400) $PN AB1
J 0
(-6390 410);
DISPLAY 0.680851 (-6390 410);
PAINT MONO (-6390 410);
FORCEPROP 2 LASTPIN (-6400 350) $PN AB22
J 0
(-6390 360);
DISPLAY 0.680851 (-6390 360);
PAINT MONO (-6390 360);
FORCEPROP 1 LAST MATERIAL IC
J 0
(-7047 2965);
DISPLAY 0.723404 (-7047 2965);
PAINT GREEN (-7047 2965);
FORCEPROP 2 LAST PART_TYPE SMLF
J 0
(-7050 3175);
DISPLAY 0.680851 (-7050 3175);
FORCEPROP 2 LAST VALUE LCMXO3LF-9400C-5BG484C
J 0
(-7050 3130);
DISPLAY 0.489362 (-7050 3130);
PAINT SKYBLUE (-7050 3130);
FORCEPROP 1 LAST CDS_LMAN_SYM_OUTLINE -250,1350,250,-1350
J 0
(-6800 1600);
DISPLAY 0.468085 (-6800 1600);
PAINT GREEN (-6800 1600);
DISPLAY INVISIBLE (-6800 1600);
FORCEPROP 1 LAST NEEDS_NO_SIZE TRUE
J 0
(-6800 1600);
DISPLAY 0.723404 (-6800 1600);
PAINT GREEN (-6800 1600);
DISPLAY INVISIBLE (-6800 1600);
FORCEPROP 2 LAST CDS_LIB pure_quanta
J 0
(-6800 1600);
DISPLAY INVISIBLE (-6800 1600);
FORCEPROP 2 LAST SEC_TYPE 
J 0
(-7025 3275);
DISPLAY 0.680851 (-7025 3275);
DISPLAY INVISIBLE (-7025 3275);
FORCEPROP 1 LAST PATH I1
J 0
(-6800 1600);
DISPLAY 0.723404 (-6800 1600);
PAINT GREEN (-6800 1600);
DISPLAY INVISIBLE (-6800 1600);
FORCEPROP 1 LAST PART_NUMBER AJ094000T08
J 0
(-7047 3092);
DISPLAY 0.723404 (-7047 3092);
PAINT GREEN (-7047 3092);
DISPLAY INVISIBLE (-7047 3092);
FORCEADD OFFPAGE..1
(-7300 4125);
FORCEPROP 2 LAST $XR0 54 
J 0
(-7521 4125);
DISPLAY 0.638298 (-7521 4125);
PAINT MONO (-7521 4125);
FORCEPROP 2 LAST CDS_LIB standard
J 0
(-7300 4125);
DISPLAY INVISIBLE (-7300 4125);
FORCEPROP 1 LAST OFFPAGE TRUE
J 0
(-6975 4000);
DISPLAY 0.872340 (-6975 4000);
PAINT GREEN (-6975 4000);
DISPLAY INVISIBLE (-6975 4000);
FORCEPROP 1 LAST COMMENT_BODY TRUE
J 0
(-7175 4025);
DISPLAY 0.872340 (-7175 4025);
PAINT GREEN (-7175 4025);
DISPLAY INVISIBLE (-7175 4025);
FORCEPROP 2 LAST PATH I10
J 0
(-7500 4175);
DISPLAY 0.680851 (-7500 4175);
DISPLAY INVISIBLE (-7500 4175);
FORCEADD Q_RES..1
(-3200 4325);
FORCEPROP 1 LAST LOCATION R223
J 0
(-3075 4325);
DISPLAY 0.489362 (-3075 4325);
PAINT SKYBLUE (-3075 4325);
FORCEPROP 0 LAST $SEC 1
J 0
(-3075 4375);
DISPLAY 0.680851 (-3075 4375);
PAINT MONO (-3075 4375);
DISPLAY INVISIBLE (-3075 4375);
FORCEPROP 0 LAST CDS_SEC 1
J 0
(-3075 4375);
DISPLAY 1.021277 (-3075 4375);
DISPLAY INVISIBLE (-3075 4375);
FORCEPROP 1 LASTPIN (-3300 4325) $PN 1
J 0
(-3288 4337);
DISPLAY 0.489362 (-3288 4337);
PAINT MONO (-3288 4337);
FORCEPROP 1 LASTPIN (-3100 4325) $PN 2
J 0
(-3138 4337);
DISPLAY 0.489362 (-3138 4337);
PAINT MONO (-3138 4337);
FORCEPROP 1 LAST VALUE 0
J 2
(-3325 4325);
DISPLAY 0.489362 (-3325 4325);
PAINT SKYBLUE (-3325 4325);
FORCEPROP 2 LAST CDS_LIB pure_quanta
J 2
(-3200 4325);
DISPLAY INVISIBLE (-3200 4325);
FORCEPROP 2 LAST BOM_COST MEM
J 2
(-3175 4475);
DISPLAY 0.744681 (-3175 4475);
PAINT WHITE (-3175 4475);
DISPLAY INVISIBLE (-3175 4475);
FORCEPROP 1 LAST WATTAGE 1/16W
J 2
(-3275 4250);
DISPLAY 0.489362 (-3275 4250);
PAINT SKYBLUE (-3275 4250);
DISPLAY INVISIBLE (-3275 4250);
FORCEPROP 1 LAST MATERIAL CHIP
J 2
(-3025 4300);
DISPLAY 0.489362 (-3025 4300);
PAINT SKYBLUE (-3025 4300);
DISPLAY INVISIBLE (-3025 4300);
FORCEPROP 1 LAST TOLERANCE 5%
J 0
(-3325 4300);
DISPLAY 0.489362 (-3325 4300);
PAINT SKYBLUE (-3325 4300);
DISPLAY INVISIBLE (-3325 4300);
FORCEPROP 1 LAST PACK_TYPE 0402LF
J 2
(-3025 4250);
DISPLAY 0.489362 (-3025 4250);
PAINT SKYBLUE (-3025 4250);
DISPLAY INVISIBLE (-3025 4250);
FORCEPROP 1 LAST PATH I100
J 0
(-3250 4475);
DISPLAY 0.978723 (-3250 4475);
PAINT WHITE (-3250 4475);
DISPLAY INVISIBLE (-3250 4475);
FORCEPROP 1 LAST PART_NUMBER CS00002JB13
J 2
(-3100 4375);
DISPLAY 0.489362 (-3100 4375);
PAINT SKYBLUE (-3100 4375);
DISPLAY INVISIBLE (-3100 4375);
FORCEADD Q_RES..1
(-3200 4375);
FORCEPROP 1 LAST LOCATION R182
J 0
(-3075 4375);
DISPLAY 0.489362 (-3075 4375);
PAINT SKYBLUE (-3075 4375);
FORCEPROP 0 LAST $SEC 1
J 2
(-3050 4425);
DISPLAY 0.680851 (-3050 4425);
PAINT MONO (-3050 4425);
DISPLAY INVISIBLE (-3050 4425);
FORCEPROP 0 LAST CDS_SEC 1
J 2
(-3050 4425);
DISPLAY 1.021277 (-3050 4425);
DISPLAY INVISIBLE (-3050 4425);
FORCEPROP 1 LASTPIN (-3300 4375) $PN 1
J 0
(-3288 4387);
DISPLAY 0.489362 (-3288 4387);
PAINT MONO (-3288 4387);
FORCEPROP 1 LASTPIN (-3100 4375) $PN 2
J 0
(-3138 4387);
DISPLAY 0.489362 (-3138 4387);
PAINT MONO (-3138 4387);
FORCEPROP 1 LAST VALUE 0
J 2
(-3325 4375);
DISPLAY 0.489362 (-3325 4375);
PAINT SKYBLUE (-3325 4375);
FORCEPROP 2 LAST BOM_COST MEM
J 2
(-3175 4525);
DISPLAY 0.744681 (-3175 4525);
PAINT WHITE (-3175 4525);
DISPLAY INVISIBLE (-3175 4525);
FORCEPROP 2 LAST CDS_LIB pure_quanta
J 2
(-3200 4375);
DISPLAY INVISIBLE (-3200 4375);
FORCEPROP 1 LAST WATTAGE 1/16W
J 2
(-3275 4300);
DISPLAY 0.489362 (-3275 4300);
PAINT SKYBLUE (-3275 4300);
DISPLAY INVISIBLE (-3275 4300);
FORCEPROP 1 LAST MATERIAL CHIP
J 2
(-3025 4350);
DISPLAY 0.489362 (-3025 4350);
PAINT SKYBLUE (-3025 4350);
DISPLAY INVISIBLE (-3025 4350);
FORCEPROP 1 LAST TOLERANCE 5%
J 0
(-3325 4350);
DISPLAY 0.489362 (-3325 4350);
PAINT SKYBLUE (-3325 4350);
DISPLAY INVISIBLE (-3325 4350);
FORCEPROP 1 LAST PACK_TYPE 0402LF
J 2
(-3025 4300);
DISPLAY 0.489362 (-3025 4300);
PAINT SKYBLUE (-3025 4300);
DISPLAY INVISIBLE (-3025 4300);
FORCEPROP 1 LAST PATH I101
J 0
(-3250 4525);
DISPLAY 0.978723 (-3250 4525);
PAINT WHITE (-3250 4525);
DISPLAY INVISIBLE (-3250 4525);
FORCEPROP 1 LAST PART_NUMBER CS00002JB13
J 2
(-3100 4425);
DISPLAY 0.489362 (-3100 4425);
PAINT SKYBLUE (-3100 4425);
DISPLAY INVISIBLE (-3100 4425);
FORCEADD Q_RES..1
(-3200 4575);
FORCEPROP 1 LAST LOCATION R6051
J 0
(-3075 4575);
DISPLAY 0.489362 (-3075 4575);
PAINT SKYBLUE (-3075 4575);
FORCEPROP 0 LAST $SEC 1
J 2
(-3075 4625);
DISPLAY 0.680851 (-3075 4625);
PAINT MONO (-3075 4625);
DISPLAY INVISIBLE (-3075 4625);
FORCEPROP 0 LAST CDS_SEC 1
J 2
(-3075 4625);
DISPLAY 1.021277 (-3075 4625);
DISPLAY INVISIBLE (-3075 4625);
FORCEPROP 1 LASTPIN (-3300 4575) $PN 1
J 0
(-3288 4587);
DISPLAY 0.489362 (-3288 4587);
PAINT MONO (-3288 4587);
FORCEPROP 1 LASTPIN (-3100 4575) $PN 2
J 0
(-3138 4587);
DISPLAY 0.489362 (-3138 4587);
PAINT MONO (-3138 4587);
FORCEPROP 1 LAST VALUE 0
J 2
(-3325 4575);
DISPLAY 0.489362 (-3325 4575);
PAINT SKYBLUE (-3325 4575);
FORCEPROP 2 LAST BOM_COST MEM
J 2
(-3175 4725);
DISPLAY 0.744681 (-3175 4725);
PAINT WHITE (-3175 4725);
DISPLAY INVISIBLE (-3175 4725);
FORCEPROP 2 LAST CDS_LIB pure_quanta
J 2
(-3200 4575);
DISPLAY INVISIBLE (-3200 4575);
FORCEPROP 1 LAST WATTAGE 1/16W
J 2
(-3275 4500);
DISPLAY 0.489362 (-3275 4500);
PAINT SKYBLUE (-3275 4500);
DISPLAY INVISIBLE (-3275 4500);
FORCEPROP 1 LAST MATERIAL CHIP
J 2
(-3025 4550);
DISPLAY 0.489362 (-3025 4550);
PAINT SKYBLUE (-3025 4550);
DISPLAY INVISIBLE (-3025 4550);
FORCEPROP 1 LAST TOLERANCE 5%
J 0
(-3325 4550);
DISPLAY 0.489362 (-3325 4550);
PAINT SKYBLUE (-3325 4550);
DISPLAY INVISIBLE (-3325 4550);
FORCEPROP 1 LAST PACK_TYPE 0402LF
J 2
(-3025 4500);
DISPLAY 0.489362 (-3025 4500);
PAINT SKYBLUE (-3025 4500);
DISPLAY INVISIBLE (-3025 4500);
FORCEPROP 1 LAST PATH I102
J 0
(-3250 4725);
DISPLAY 0.978723 (-3250 4725);
PAINT WHITE (-3250 4725);
DISPLAY INVISIBLE (-3250 4725);
FORCEPROP 1 LAST PART_NUMBER CS00002JB13
J 2
(-3100 4625);
DISPLAY 0.489362 (-3100 4625);
PAINT SKYBLUE (-3100 4625);
DISPLAY INVISIBLE (-3100 4625);
FORCEADD Q_RES..1
(-3200 4975);
FORCEPROP 1 LAST LOCATION R227
J 0
(-3075 4975);
DISPLAY 0.489362 (-3075 4975);
PAINT SKYBLUE (-3075 4975);
FORCEPROP 0 LAST $SEC 1
J 2
(-3075 5025);
DISPLAY 0.680851 (-3075 5025);
PAINT MONO (-3075 5025);
DISPLAY INVISIBLE (-3075 5025);
FORCEPROP 0 LAST CDS_SEC 1
J 2
(-3075 5025);
DISPLAY 1.021277 (-3075 5025);
DISPLAY INVISIBLE (-3075 5025);
FORCEPROP 1 LASTPIN (-3300 4975) $PN 1
J 0
(-3288 4987);
DISPLAY 0.489362 (-3288 4987);
PAINT MONO (-3288 4987);
FORCEPROP 1 LASTPIN (-3100 4975) $PN 2
J 0
(-3138 4987);
DISPLAY 0.489362 (-3138 4987);
PAINT MONO (-3138 4987);
FORCEPROP 1 LAST VALUE 33
J 2
(-3325 4975);
DISPLAY 0.489362 (-3325 4975);
PAINT SKYBLUE (-3325 4975);
FORCEPROP 2 LAST BOM_COST MEM
J 2
(-3175 5125);
DISPLAY 0.744681 (-3175 5125);
PAINT WHITE (-3175 5125);
DISPLAY INVISIBLE (-3175 5125);
FORCEPROP 2 LAST CDS_LIB pure_quanta
J 2
(-3200 4975);
DISPLAY INVISIBLE (-3200 4975);
FORCEPROP 1 LAST WATTAGE 1/16W
J 2
(-3275 4900);
DISPLAY 0.489362 (-3275 4900);
PAINT SKYBLUE (-3275 4900);
DISPLAY INVISIBLE (-3275 4900);
FORCEPROP 1 LAST MATERIAL CHIP
J 2
(-3025 4950);
DISPLAY 0.489362 (-3025 4950);
PAINT SKYBLUE (-3025 4950);
DISPLAY INVISIBLE (-3025 4950);
FORCEPROP 1 LAST TOLERANCE 5%
J 0
(-3325 4950);
DISPLAY 0.489362 (-3325 4950);
PAINT SKYBLUE (-3325 4950);
DISPLAY INVISIBLE (-3325 4950);
FORCEPROP 1 LAST PACK_TYPE 0402LF
J 2
(-3025 4900);
DISPLAY 0.489362 (-3025 4900);
PAINT SKYBLUE (-3025 4900);
DISPLAY INVISIBLE (-3025 4900);
FORCEPROP 1 LAST PATH I103
J 0
(-3250 5125);
DISPLAY 0.978723 (-3250 5125);
PAINT WHITE (-3250 5125);
DISPLAY INVISIBLE (-3250 5125);
FORCEPROP 1 LAST PART_NUMBER CS03302JB10
J 2
(-3100 5025);
DISPLAY 0.489362 (-3100 5025);
PAINT SKYBLUE (-3100 5025);
DISPLAY INVISIBLE (-3100 5025);
FORCEADD Q_RES..1
(-3200 5025);
FORCEPROP 1 LAST LOCATION R271
J 0
(-3075 5025);
DISPLAY 0.489362 (-3075 5025);
PAINT SKYBLUE (-3075 5025);
FORCEPROP 0 LAST $SEC 1
J 2
(-3075 5075);
DISPLAY 0.680851 (-3075 5075);
PAINT MONO (-3075 5075);
DISPLAY INVISIBLE (-3075 5075);
FORCEPROP 0 LAST CDS_SEC 1
J 2
(-3075 5075);
DISPLAY 1.021277 (-3075 5075);
DISPLAY INVISIBLE (-3075 5075);
FORCEPROP 1 LASTPIN (-3300 5025) $PN 1
J 0
(-3288 5037);
DISPLAY 0.489362 (-3288 5037);
PAINT MONO (-3288 5037);
FORCEPROP 1 LASTPIN (-3100 5025) $PN 2
J 0
(-3138 5037);
DISPLAY 0.489362 (-3138 5037);
PAINT MONO (-3138 5037);
FORCEPROP 1 LAST VALUE 0
J 2
(-3325 5025);
DISPLAY 0.489362 (-3325 5025);
PAINT SKYBLUE (-3325 5025);
FORCEPROP 2 LAST BOM_COST MEM
J 2
(-3175 5175);
DISPLAY 0.744681 (-3175 5175);
PAINT WHITE (-3175 5175);
DISPLAY INVISIBLE (-3175 5175);
FORCEPROP 1 LAST WATTAGE 1/16W
J 2
(-3275 4950);
DISPLAY 0.489362 (-3275 4950);
PAINT SKYBLUE (-3275 4950);
DISPLAY INVISIBLE (-3275 4950);
FORCEPROP 1 LAST MATERIAL CHIP
J 2
(-3025 5000);
DISPLAY 0.489362 (-3025 5000);
PAINT SKYBLUE (-3025 5000);
DISPLAY INVISIBLE (-3025 5000);
FORCEPROP 1 LAST TOLERANCE 5%
J 0
(-3325 5000);
DISPLAY 0.489362 (-3325 5000);
PAINT SKYBLUE (-3325 5000);
DISPLAY INVISIBLE (-3325 5000);
FORCEPROP 1 LAST PACK_TYPE 0402LF
J 2
(-3025 4950);
DISPLAY 0.489362 (-3025 4950);
PAINT SKYBLUE (-3025 4950);
DISPLAY INVISIBLE (-3025 4950);
FORCEPROP 2 LAST CDS_LIB pure_quanta
J 2
(-3200 5025);
DISPLAY INVISIBLE (-3200 5025);
FORCEPROP 1 LAST PATH I104
J 0
(-3250 5175);
DISPLAY 0.978723 (-3250 5175);
PAINT WHITE (-3250 5175);
DISPLAY INVISIBLE (-3250 5175);
FORCEPROP 1 LAST PART_NUMBER CS00002JB13
J 2
(-3100 5075);
DISPLAY 0.489362 (-3100 5075);
PAINT SKYBLUE (-3100 5075);
DISPLAY INVISIBLE (-3100 5075);
FORCEADD Q_RES..1
(-3200 5075);
FORCEPROP 1 LAST LOCATION R285
J 0
(-3075 5075);
DISPLAY 0.489362 (-3075 5075);
PAINT SKYBLUE (-3075 5075);
FORCEPROP 0 LAST $SEC 1
J 2
(-3075 5125);
DISPLAY 0.680851 (-3075 5125);
PAINT MONO (-3075 5125);
DISPLAY INVISIBLE (-3075 5125);
FORCEPROP 0 LAST CDS_SEC 1
J 2
(-3075 5125);
DISPLAY 1.021277 (-3075 5125);
DISPLAY INVISIBLE (-3075 5125);
FORCEPROP 1 LASTPIN (-3300 5075) $PN 1
J 0
(-3288 5087);
DISPLAY 0.489362 (-3288 5087);
PAINT MONO (-3288 5087);
FORCEPROP 1 LASTPIN (-3100 5075) $PN 2
J 0
(-3138 5087);
DISPLAY 0.489362 (-3138 5087);
PAINT MONO (-3138 5087);
FORCEPROP 1 LAST VALUE 33
J 2
(-3325 5075);
DISPLAY 0.489362 (-3325 5075);
PAINT SKYBLUE (-3325 5075);
FORCEPROP 2 LAST CDS_LIB pure_quanta
J 2
(-3200 5075);
DISPLAY INVISIBLE (-3200 5075);
FORCEPROP 2 LAST BOM_COST MEM
J 2
(-3175 5225);
DISPLAY 0.744681 (-3175 5225);
PAINT WHITE (-3175 5225);
DISPLAY INVISIBLE (-3175 5225);
FORCEPROP 1 LAST WATTAGE 1/16W
J 2
(-3275 5000);
DISPLAY 0.489362 (-3275 5000);
PAINT SKYBLUE (-3275 5000);
DISPLAY INVISIBLE (-3275 5000);
FORCEPROP 1 LAST MATERIAL CHIP
J 2
(-3025 5050);
DISPLAY 0.489362 (-3025 5050);
PAINT SKYBLUE (-3025 5050);
DISPLAY INVISIBLE (-3025 5050);
FORCEPROP 1 LAST TOLERANCE 5%
J 0
(-3325 5050);
DISPLAY 0.489362 (-3325 5050);
PAINT SKYBLUE (-3325 5050);
DISPLAY INVISIBLE (-3325 5050);
FORCEPROP 1 LAST PACK_TYPE 0402LF
J 2
(-3025 5000);
DISPLAY 0.489362 (-3025 5000);
PAINT SKYBLUE (-3025 5000);
DISPLAY INVISIBLE (-3025 5000);
FORCEPROP 1 LAST PATH I105
J 0
(-3250 5225);
DISPLAY 0.978723 (-3250 5225);
PAINT WHITE (-3250 5225);
DISPLAY INVISIBLE (-3250 5225);
FORCEPROP 1 LAST PART_NUMBER CS03302JB10
J 2
(-3100 5125);
DISPLAY 0.489362 (-3100 5125);
PAINT SKYBLUE (-3100 5125);
DISPLAY INVISIBLE (-3100 5125);
FORCEADD Q_RES..1
(-3250 5575);
FORCEPROP 1 LAST LOCATION R81
J 0
(-3125 5575);
DISPLAY 0.489362 (-3125 5575);
PAINT SKYBLUE (-3125 5575);
FORCEPROP 0 LAST $SEC 1
J 0
(-3125 5600);
DISPLAY 0.680851 (-3125 5600);
PAINT MONO (-3125 5600);
DISPLAY INVISIBLE (-3125 5600);
FORCEPROP 0 LAST CDS_SEC 1
J 0
(-3125 5600);
DISPLAY 0.680851 (-3125 5600);
DISPLAY INVISIBLE (-3125 5600);
FORCEPROP 1 LASTPIN (-3350 5575) $PN 1
J 0
(-3338 5587);
DISPLAY 0.489362 (-3338 5587);
PAINT MONO (-3338 5587);
FORCEPROP 1 LASTPIN (-3150 5575) $PN 2
J 0
(-3188 5587);
DISPLAY 0.489362 (-3188 5587);
PAINT MONO (-3188 5587);
FORCEPROP 1 LAST VALUE 33
J 2
(-3375 5575);
DISPLAY 0.489362 (-3375 5575);
PAINT SKYBLUE (-3375 5575);
FORCEPROP 2 LAST CDS_LIB pure_quanta
J 0
(-3250 5575);
DISPLAY INVISIBLE (-3250 5575);
FORCEPROP 2 LAST BOM_COST MEM
J 2
(-3225 5725);
DISPLAY 0.744681 (-3225 5725);
PAINT WHITE (-3225 5725);
DISPLAY INVISIBLE (-3225 5725);
FORCEPROP 1 LAST WATTAGE 1/16W
J 2
(-3325 5500);
DISPLAY 0.489362 (-3325 5500);
PAINT SKYBLUE (-3325 5500);
DISPLAY INVISIBLE (-3325 5500);
FORCEPROP 1 LAST MATERIAL CHIP
J 2
(-3075 5550);
DISPLAY 0.489362 (-3075 5550);
PAINT SKYBLUE (-3075 5550);
DISPLAY INVISIBLE (-3075 5550);
FORCEPROP 1 LAST TOLERANCE 5%
J 0
(-3375 5550);
DISPLAY 0.489362 (-3375 5550);
PAINT SKYBLUE (-3375 5550);
DISPLAY INVISIBLE (-3375 5550);
FORCEPROP 1 LAST PACK_TYPE 0402LF
J 2
(-3075 5500);
DISPLAY 0.489362 (-3075 5500);
PAINT SKYBLUE (-3075 5500);
DISPLAY INVISIBLE (-3075 5500);
FORCEPROP 1 LAST PATH I106
J 0
(-3300 5725);
DISPLAY 0.978723 (-3300 5725);
PAINT WHITE (-3300 5725);
DISPLAY INVISIBLE (-3300 5725);
FORCEPROP 1 LAST PART_NUMBER CS03302JB10
J 2
(-3150 5625);
DISPLAY 0.489362 (-3150 5625);
PAINT SKYBLUE (-3150 5625);
DISPLAY INVISIBLE (-3150 5625);
FORCEADD Q_RES..1
(-3250 5525);
FORCEPROP 1 LAST LOCATION R221
J 0
(-3125 5525);
DISPLAY 0.489362 (-3125 5525);
PAINT SKYBLUE (-3125 5525);
FORCEPROP 0 LAST $SEC 1
J 0
(-3125 5550);
DISPLAY 0.680851 (-3125 5550);
PAINT MONO (-3125 5550);
DISPLAY INVISIBLE (-3125 5550);
FORCEPROP 0 LAST CDS_SEC 1
J 0
(-3125 5550);
DISPLAY 0.680851 (-3125 5550);
DISPLAY INVISIBLE (-3125 5550);
FORCEPROP 1 LASTPIN (-3350 5525) $PN 1
J 0
(-3338 5537);
DISPLAY 0.510638 (-3338 5537);
PAINT MONO (-3338 5537);
FORCEPROP 1 LASTPIN (-3150 5525) $PN 2
J 0
(-3188 5537);
DISPLAY 0.510638 (-3188 5537);
PAINT MONO (-3188 5537);
FORCEPROP 1 LAST VALUE 33
J 2
(-3375 5525);
DISPLAY 0.489362 (-3375 5525);
PAINT SKYBLUE (-3375 5525);
FORCEPROP 2 LAST BOM_COST MEM
J 2
(-3225 5675);
DISPLAY 0.744681 (-3225 5675);
PAINT WHITE (-3225 5675);
DISPLAY INVISIBLE (-3225 5675);
FORCEPROP 1 LAST WATTAGE 1/16W
J 2
(-3325 5450);
DISPLAY 0.489362 (-3325 5450);
PAINT SKYBLUE (-3325 5450);
DISPLAY INVISIBLE (-3325 5450);
FORCEPROP 1 LAST MATERIAL CHIP
J 2
(-3075 5500);
DISPLAY 0.489362 (-3075 5500);
PAINT SKYBLUE (-3075 5500);
DISPLAY INVISIBLE (-3075 5500);
FORCEPROP 1 LAST TOLERANCE 5%
J 0
(-3375 5500);
DISPLAY 0.489362 (-3375 5500);
PAINT SKYBLUE (-3375 5500);
DISPLAY INVISIBLE (-3375 5500);
FORCEPROP 1 LAST PACK_TYPE 0402LF
J 2
(-3075 5450);
DISPLAY 0.489362 (-3075 5450);
PAINT SKYBLUE (-3075 5450);
DISPLAY INVISIBLE (-3075 5450);
FORCEPROP 2 LAST CDS_LIB pure_quanta
J 0
(-3250 5525);
DISPLAY INVISIBLE (-3250 5525);
FORCEPROP 1 LAST PATH I107
J 0
(-3300 5675);
DISPLAY 0.978723 (-3300 5675);
PAINT WHITE (-3300 5675);
DISPLAY INVISIBLE (-3300 5675);
FORCEPROP 1 LAST PART_NUMBER CS03302JB10
J 2
(-3150 5575);
DISPLAY 0.489362 (-3150 5575);
PAINT SKYBLUE (-3150 5575);
DISPLAY INVISIBLE (-3150 5575);
FORCEADD Q_RES..1
(-3250 5825);
FORCEPROP 1 LAST LOCATION R266
J 0
(-3125 5825);
DISPLAY 0.489362 (-3125 5825);
PAINT SKYBLUE (-3125 5825);
FORCEPROP 0 LAST $SEC 1
J 0
(-3125 5850);
DISPLAY 0.680851 (-3125 5850);
PAINT MONO (-3125 5850);
DISPLAY INVISIBLE (-3125 5850);
FORCEPROP 0 LAST CDS_SEC 1
J 0
(-3125 5850);
DISPLAY 0.680851 (-3125 5850);
DISPLAY INVISIBLE (-3125 5850);
FORCEPROP 1 LASTPIN (-3350 5825) $PN 1
J 0
(-3338 5837);
DISPLAY 0.510638 (-3338 5837);
PAINT MONO (-3338 5837);
FORCEPROP 1 LASTPIN (-3150 5825) $PN 2
J 0
(-3188 5837);
DISPLAY 0.510638 (-3188 5837);
PAINT MONO (-3188 5837);
FORCEPROP 1 LAST VALUE 33
J 2
(-3375 5825);
DISPLAY 0.489362 (-3375 5825);
PAINT SKYBLUE (-3375 5825);
FORCEPROP 1 LAST PACK_TYPE 0402LF
J 2
(-3075 5750);
DISPLAY 0.489362 (-3075 5750);
PAINT SKYBLUE (-3075 5750);
DISPLAY INVISIBLE (-3075 5750);
FORCEPROP 1 LAST TOLERANCE 5%
J 0
(-3375 5800);
DISPLAY 0.489362 (-3375 5800);
PAINT SKYBLUE (-3375 5800);
DISPLAY INVISIBLE (-3375 5800);
FORCEPROP 1 LAST MATERIAL CHIP
J 2
(-3075 5800);
DISPLAY 0.489362 (-3075 5800);
PAINT SKYBLUE (-3075 5800);
DISPLAY INVISIBLE (-3075 5800);
FORCEPROP 1 LAST WATTAGE 1/16W
J 2
(-3325 5750);
DISPLAY 0.489362 (-3325 5750);
PAINT SKYBLUE (-3325 5750);
DISPLAY INVISIBLE (-3325 5750);
FORCEPROP 2 LAST BOM_COST MEM
J 2
(-3225 5975);
DISPLAY 0.744681 (-3225 5975);
PAINT WHITE (-3225 5975);
DISPLAY INVISIBLE (-3225 5975);
FORCEPROP 2 LAST CDS_LIB pure_quanta
J 0
(-3250 5825);
DISPLAY INVISIBLE (-3250 5825);
FORCEPROP 1 LAST PATH I108
J 0
(-3300 5975);
DISPLAY 0.978723 (-3300 5975);
PAINT WHITE (-3300 5975);
DISPLAY INVISIBLE (-3300 5975);
FORCEPROP 1 LAST PART_NUMBER CS03302JB10
J 2
(-3150 5875);
DISPLAY 0.489362 (-3150 5875);
PAINT SKYBLUE (-3150 5875);
DISPLAY INVISIBLE (-3150 5875);
FORCEADD Q_RES..1
(-3250 5725);
FORCEPROP 1 LAST LOCATION R220
J 0
(-3125 5725);
DISPLAY 0.489362 (-3125 5725);
PAINT SKYBLUE (-3125 5725);
FORCEPROP 0 LAST $SEC 1
J 0
(-3125 5750);
DISPLAY 0.680851 (-3125 5750);
PAINT MONO (-3125 5750);
DISPLAY INVISIBLE (-3125 5750);
FORCEPROP 0 LAST CDS_SEC 1
J 0
(-3125 5750);
DISPLAY 0.680851 (-3125 5750);
DISPLAY INVISIBLE (-3125 5750);
FORCEPROP 1 LASTPIN (-3350 5725) $PN 1
J 0
(-3338 5737);
DISPLAY 0.510638 (-3338 5737);
PAINT MONO (-3338 5737);
FORCEPROP 1 LASTPIN (-3150 5725) $PN 2
J 0
(-3188 5737);
DISPLAY 0.510638 (-3188 5737);
PAINT MONO (-3188 5737);
FORCEPROP 1 LAST VALUE 33
J 2
(-3375 5725);
DISPLAY 0.489362 (-3375 5725);
PAINT SKYBLUE (-3375 5725);
FORCEPROP 2 LAST BOM_COST MEM
J 2
(-3225 5875);
DISPLAY 0.744681 (-3225 5875);
PAINT WHITE (-3225 5875);
DISPLAY INVISIBLE (-3225 5875);
FORCEPROP 1 LAST WATTAGE 1/16W
J 2
(-3325 5650);
DISPLAY 0.489362 (-3325 5650);
PAINT SKYBLUE (-3325 5650);
DISPLAY INVISIBLE (-3325 5650);
FORCEPROP 1 LAST MATERIAL CHIP
J 2
(-3075 5700);
DISPLAY 0.489362 (-3075 5700);
PAINT SKYBLUE (-3075 5700);
DISPLAY INVISIBLE (-3075 5700);
FORCEPROP 1 LAST TOLERANCE 5%
J 0
(-3375 5700);
DISPLAY 0.489362 (-3375 5700);
PAINT SKYBLUE (-3375 5700);
DISPLAY INVISIBLE (-3375 5700);
FORCEPROP 1 LAST PACK_TYPE 0402LF
J 2
(-3075 5650);
DISPLAY 0.489362 (-3075 5650);
PAINT SKYBLUE (-3075 5650);
DISPLAY INVISIBLE (-3075 5650);
FORCEPROP 2 LAST CDS_LIB pure_quanta
J 0
(-3250 5725);
DISPLAY INVISIBLE (-3250 5725);
FORCEPROP 1 LAST PATH I109
J 0
(-3300 5875);
DISPLAY 0.978723 (-3300 5875);
PAINT WHITE (-3300 5875);
DISPLAY INVISIBLE (-3300 5875);
FORCEPROP 1 LAST PART_NUMBER CS03302JB10
J 2
(-3150 5775);
DISPLAY 0.489362 (-3150 5775);
PAINT SKYBLUE (-3150 5775);
DISPLAY INVISIBLE (-3150 5775);
FORCEADD OFFPAGE..1
(-7300 4175);
FORCEPROP 2 LAST $XR0 27 
J 0
(-7521 4175);
DISPLAY 0.638298 (-7521 4175);
PAINT MONO (-7521 4175);
FORCEPROP 2 LAST CDS_LIB standard
J 0
(-7300 4175);
DISPLAY INVISIBLE (-7300 4175);
FORCEPROP 1 LAST OFFPAGE TRUE
J 0
(-6975 4050);
DISPLAY 0.872340 (-6975 4050);
PAINT GREEN (-6975 4050);
DISPLAY INVISIBLE (-6975 4050);
FORCEPROP 1 LAST COMMENT_BODY TRUE
J 0
(-7175 4075);
DISPLAY 0.872340 (-7175 4075);
PAINT GREEN (-7175 4075);
DISPLAY INVISIBLE (-7175 4075);
FORCEPROP 2 LAST PATH I11
J 0
(-7500 4225);
DISPLAY 0.680851 (-7500 4225);
DISPLAY INVISIBLE (-7500 4225);
FORCEADD Q_RES..1
(-3250 5775);
FORCEPROP 1 LAST LOCATION R179
J 0
(-3125 5775);
DISPLAY 0.489362 (-3125 5775);
PAINT SKYBLUE (-3125 5775);
FORCEPROP 0 LAST $SEC 1
J 2
(-3125 5825);
DISPLAY 0.680851 (-3125 5825);
PAINT MONO (-3125 5825);
DISPLAY INVISIBLE (-3125 5825);
FORCEPROP 0 LAST CDS_SEC 1
J 2
(-3125 5825);
DISPLAY 1.021277 (-3125 5825);
DISPLAY INVISIBLE (-3125 5825);
FORCEPROP 1 LASTPIN (-3350 5775) $PN 1
J 0
(-3338 5787);
DISPLAY 0.489362 (-3338 5787);
PAINT MONO (-3338 5787);
FORCEPROP 1 LASTPIN (-3150 5775) $PN 2
J 0
(-3188 5787);
DISPLAY 0.489362 (-3188 5787);
PAINT MONO (-3188 5787);
FORCEPROP 1 LAST VALUE 33
J 2
(-3375 5775);
DISPLAY 0.489362 (-3375 5775);
PAINT SKYBLUE (-3375 5775);
FORCEPROP 2 LAST BOM_COST MEM
J 2
(-3225 5925);
DISPLAY 0.744681 (-3225 5925);
PAINT WHITE (-3225 5925);
DISPLAY INVISIBLE (-3225 5925);
FORCEPROP 2 LAST CDS_LIB pure_quanta
J 2
(-3250 5775);
DISPLAY INVISIBLE (-3250 5775);
FORCEPROP 1 LAST WATTAGE 1/16W
J 2
(-3325 5700);
DISPLAY 0.489362 (-3325 5700);
PAINT SKYBLUE (-3325 5700);
DISPLAY INVISIBLE (-3325 5700);
FORCEPROP 1 LAST MATERIAL CHIP
J 2
(-3075 5750);
DISPLAY 0.489362 (-3075 5750);
PAINT SKYBLUE (-3075 5750);
DISPLAY INVISIBLE (-3075 5750);
FORCEPROP 1 LAST TOLERANCE 5%
J 0
(-3375 5750);
DISPLAY 0.489362 (-3375 5750);
PAINT SKYBLUE (-3375 5750);
DISPLAY INVISIBLE (-3375 5750);
FORCEPROP 1 LAST PACK_TYPE 0402LF
J 2
(-3075 5700);
DISPLAY 0.489362 (-3075 5700);
PAINT SKYBLUE (-3075 5700);
DISPLAY INVISIBLE (-3075 5700);
FORCEPROP 1 LAST PATH I110
J 0
(-3300 5925);
DISPLAY 0.978723 (-3300 5925);
PAINT WHITE (-3300 5925);
DISPLAY INVISIBLE (-3300 5925);
FORCEPROP 1 LAST PART_NUMBER CS03302JB10
J 2
(-3150 5825);
DISPLAY 0.489362 (-3150 5825);
PAINT SKYBLUE (-3150 5825);
DISPLAY INVISIBLE (-3150 5825);
FORCEADD Q_RES..1
(-3250 5975);
FORCEPROP 1 LAST LOCATION R226
J 0
(-3125 5975);
DISPLAY 0.489362 (-3125 5975);
PAINT SKYBLUE (-3125 5975);
FORCEPROP 0 LAST $SEC 1
J 0
(-3125 6025);
DISPLAY 0.680851 (-3125 6025);
PAINT MONO (-3125 6025);
DISPLAY INVISIBLE (-3125 6025);
FORCEPROP 0 LAST CDS_SEC 1
J 0
(-3125 6025);
DISPLAY 1.021277 (-3125 6025);
DISPLAY INVISIBLE (-3125 6025);
FORCEPROP 1 LASTPIN (-3350 5975) $PN 1
J 0
(-3338 5987);
DISPLAY 0.489362 (-3338 5987);
PAINT MONO (-3338 5987);
FORCEPROP 1 LASTPIN (-3150 5975) $PN 2
J 0
(-3188 5987);
DISPLAY 0.489362 (-3188 5987);
PAINT MONO (-3188 5987);
FORCEPROP 1 LAST VALUE 0
J 2
(-3375 5975);
DISPLAY 0.489362 (-3375 5975);
PAINT SKYBLUE (-3375 5975);
FORCEPROP 2 LAST CDS_LIB pure_quanta
J 2
(-3250 5975);
DISPLAY INVISIBLE (-3250 5975);
FORCEPROP 2 LAST BOM_COST MEM
J 2
(-3225 6125);
DISPLAY 0.744681 (-3225 6125);
PAINT WHITE (-3225 6125);
DISPLAY INVISIBLE (-3225 6125);
FORCEPROP 1 LAST WATTAGE 1/16W
J 2
(-3325 5900);
DISPLAY 0.489362 (-3325 5900);
PAINT SKYBLUE (-3325 5900);
DISPLAY INVISIBLE (-3325 5900);
FORCEPROP 1 LAST MATERIAL CHIP
J 2
(-3075 5950);
DISPLAY 0.489362 (-3075 5950);
PAINT SKYBLUE (-3075 5950);
DISPLAY INVISIBLE (-3075 5950);
FORCEPROP 1 LAST TOLERANCE 5%
J 0
(-3375 5950);
DISPLAY 0.489362 (-3375 5950);
PAINT SKYBLUE (-3375 5950);
DISPLAY INVISIBLE (-3375 5950);
FORCEPROP 1 LAST PACK_TYPE 0402LF
J 2
(-3075 5900);
DISPLAY 0.489362 (-3075 5900);
PAINT SKYBLUE (-3075 5900);
DISPLAY INVISIBLE (-3075 5900);
FORCEPROP 1 LAST PATH I111
J 0
(-3300 6125);
DISPLAY 0.978723 (-3300 6125);
PAINT WHITE (-3300 6125);
DISPLAY INVISIBLE (-3300 6125);
FORCEPROP 1 LAST PART_NUMBER CS00002JB13
J 2
(-3150 6025);
DISPLAY 0.489362 (-3150 6025);
PAINT SKYBLUE (-3150 6025);
DISPLAY INVISIBLE (-3150 6025);
FORCEADD Q_RES..1
(-3250 6075);
FORCEPROP 1 LAST LOCATION R270
J 0
(-3125 6075);
DISPLAY 0.489362 (-3125 6075);
PAINT SKYBLUE (-3125 6075);
FORCEPROP 0 LAST $SEC 1
J 2
(-3125 6125);
DISPLAY 0.680851 (-3125 6125);
PAINT MONO (-3125 6125);
DISPLAY INVISIBLE (-3125 6125);
FORCEPROP 0 LAST CDS_SEC 1
J 2
(-3125 6125);
DISPLAY 1.021277 (-3125 6125);
DISPLAY INVISIBLE (-3125 6125);
FORCEPROP 1 LASTPIN (-3350 6075) $PN 1
J 0
(-3338 6087);
DISPLAY 0.489362 (-3338 6087);
PAINT MONO (-3338 6087);
FORCEPROP 1 LASTPIN (-3150 6075) $PN 2
J 0
(-3188 6087);
DISPLAY 0.489362 (-3188 6087);
PAINT MONO (-3188 6087);
FORCEPROP 1 LAST VALUE 33
J 2
(-3375 6075);
DISPLAY 0.489362 (-3375 6075);
PAINT SKYBLUE (-3375 6075);
FORCEPROP 2 LAST BOM_COST MEM
J 2
(-3225 6225);
DISPLAY 0.744681 (-3225 6225);
PAINT WHITE (-3225 6225);
DISPLAY INVISIBLE (-3225 6225);
FORCEPROP 2 LAST CDS_LIB pure_quanta
J 2
(-3250 6075);
DISPLAY INVISIBLE (-3250 6075);
FORCEPROP 1 LAST WATTAGE 1/16W
J 2
(-3325 6000);
DISPLAY 0.489362 (-3325 6000);
PAINT SKYBLUE (-3325 6000);
DISPLAY INVISIBLE (-3325 6000);
FORCEPROP 1 LAST MATERIAL CHIP
J 2
(-3075 6050);
DISPLAY 0.489362 (-3075 6050);
PAINT SKYBLUE (-3075 6050);
DISPLAY INVISIBLE (-3075 6050);
FORCEPROP 1 LAST TOLERANCE 5%
J 0
(-3375 6050);
DISPLAY 0.489362 (-3375 6050);
PAINT SKYBLUE (-3375 6050);
DISPLAY INVISIBLE (-3375 6050);
FORCEPROP 1 LAST PACK_TYPE 0402LF
J 2
(-3075 6000);
DISPLAY 0.489362 (-3075 6000);
PAINT SKYBLUE (-3075 6000);
DISPLAY INVISIBLE (-3075 6000);
FORCEPROP 1 LAST PATH I112
J 0
(-3300 6225);
DISPLAY 0.978723 (-3300 6225);
PAINT WHITE (-3300 6225);
DISPLAY INVISIBLE (-3300 6225);
FORCEPROP 1 LAST PART_NUMBER CS03302JB10
J 2
(-3150 6125);
DISPLAY 0.489362 (-3150 6125);
PAINT SKYBLUE (-3150 6125);
DISPLAY INVISIBLE (-3150 6125);
FORCEADD Q_RES..1
(-3250 6025);
FORCEPROP 1 LAST LOCATION R278
J 0
(-3125 6025);
DISPLAY 0.489362 (-3125 6025);
PAINT SKYBLUE (-3125 6025);
FORCEPROP 0 LAST $SEC 1
J 0
(-3125 6075);
DISPLAY 0.680851 (-3125 6075);
PAINT MONO (-3125 6075);
DISPLAY INVISIBLE (-3125 6075);
FORCEPROP 0 LAST CDS_SEC 1
J 0
(-3125 6075);
DISPLAY 1.021277 (-3125 6075);
DISPLAY INVISIBLE (-3125 6075);
FORCEPROP 1 LASTPIN (-3350 6025) $PN 1
J 0
(-3338 6037);
DISPLAY 0.489362 (-3338 6037);
PAINT MONO (-3338 6037);
FORCEPROP 1 LASTPIN (-3150 6025) $PN 2
J 0
(-3188 6037);
DISPLAY 0.489362 (-3188 6037);
PAINT MONO (-3188 6037);
FORCEPROP 1 LAST VALUE 0
J 2
(-3375 6025);
DISPLAY 0.489362 (-3375 6025);
PAINT SKYBLUE (-3375 6025);
FORCEPROP 2 LAST CDS_LIB pure_quanta
J 2
(-3250 6025);
DISPLAY INVISIBLE (-3250 6025);
FORCEPROP 2 LAST BOM_COST MEM
J 2
(-3225 6175);
DISPLAY 0.744681 (-3225 6175);
PAINT WHITE (-3225 6175);
DISPLAY INVISIBLE (-3225 6175);
FORCEPROP 1 LAST WATTAGE 1/16W
J 2
(-3325 5950);
DISPLAY 0.489362 (-3325 5950);
PAINT SKYBLUE (-3325 5950);
DISPLAY INVISIBLE (-3325 5950);
FORCEPROP 1 LAST MATERIAL CHIP
J 2
(-3075 6000);
DISPLAY 0.489362 (-3075 6000);
PAINT SKYBLUE (-3075 6000);
DISPLAY INVISIBLE (-3075 6000);
FORCEPROP 1 LAST TOLERANCE 5%
J 0
(-3375 6000);
DISPLAY 0.489362 (-3375 6000);
PAINT SKYBLUE (-3375 6000);
DISPLAY INVISIBLE (-3375 6000);
FORCEPROP 1 LAST PACK_TYPE 0402LF
J 2
(-3075 5950);
DISPLAY 0.489362 (-3075 5950);
PAINT SKYBLUE (-3075 5950);
DISPLAY INVISIBLE (-3075 5950);
FORCEPROP 1 LAST PATH I113
J 0
(-3300 6175);
DISPLAY 0.978723 (-3300 6175);
PAINT WHITE (-3300 6175);
DISPLAY INVISIBLE (-3300 6175);
FORCEPROP 1 LAST PART_NUMBER CS00002JB13
J 2
(-3150 6075);
DISPLAY 0.489362 (-3150 6075);
PAINT SKYBLUE (-3150 6075);
DISPLAY INVISIBLE (-3150 6075);
FORCEADD OFFPAGE..1
R 2
(-2325 4325);
FORCEPROP 2 LAST $XR0 27 
J 0
(-2139 4325);
DISPLAY 0.638298 (-2139 4325);
PAINT MONO (-2139 4325);
FORCEPROP 2 LAST CDS_LIB standard
J 0
(-2325 4325);
DISPLAY INVISIBLE (-2325 4325);
FORCEPROP 1 LAST OFFPAGE TRUE
J 2
(-2650 4200);
DISPLAY 0.872340 (-2650 4200);
PAINT GREEN (-2650 4200);
DISPLAY INVISIBLE (-2650 4200);
FORCEPROP 1 LAST COMMENT_BODY TRUE
J 2
(-2450 4225);
DISPLAY 0.872340 (-2450 4225);
PAINT GREEN (-2450 4225);
DISPLAY INVISIBLE (-2450 4225);
FORCEPROP 2 LAST PATH I114
J 0
(-2125 4375);
DISPLAY 0.680851 (-2125 4375);
DISPLAY INVISIBLE (-2125 4375);
FORCEADD OFFPAGE..1
R 2
(-2325 4425);
FORCEPROP 2 LAST $XR2 80 
J 0
(-1929 4425);
DISPLAY 0.638298 (-1929 4425);
PAINT MONO (-1929 4425);
FORCEPROP 2 LAST $XR1 145 
J 0
(-2049 4425);
DISPLAY 0.638298 (-2049 4425);
PAINT MONO (-2049 4425);
FORCEPROP 2 LAST $XR0 83 
J 0
(-2139 4425);
DISPLAY 0.638298 (-2139 4425);
PAINT MONO (-2139 4425);
FORCEPROP 2 LAST CDS_LIB standard
J 0
(-2325 4425);
DISPLAY INVISIBLE (-2325 4425);
FORCEPROP 1 LAST OFFPAGE TRUE
J 2
(-2650 4300);
DISPLAY 0.872340 (-2650 4300);
PAINT GREEN (-2650 4300);
DISPLAY INVISIBLE (-2650 4300);
FORCEPROP 1 LAST COMMENT_BODY TRUE
J 2
(-2450 4325);
DISPLAY 0.872340 (-2450 4325);
PAINT GREEN (-2450 4325);
DISPLAY INVISIBLE (-2450 4325);
FORCEPROP 2 LAST PATH I115
J 0
(-2025 4475);
DISPLAY 0.680851 (-2025 4475);
DISPLAY INVISIBLE (-2025 4475);
FORCEADD OFFPAGE..1
R 2
(-2325 4525);
FORCEPROP 2 LAST $XR0 86 
J 0
(-2139 4525);
DISPLAY 0.638298 (-2139 4525);
PAINT MONO (-2139 4525);
FORCEPROP 2 LAST CDS_LIB standard
J 0
(-2325 4525);
DISPLAY INVISIBLE (-2325 4525);
FORCEPROP 1 LAST OFFPAGE TRUE
J 2
(-2650 4400);
DISPLAY 0.872340 (-2650 4400);
PAINT GREEN (-2650 4400);
DISPLAY INVISIBLE (-2650 4400);
FORCEPROP 1 LAST COMMENT_BODY TRUE
J 2
(-2450 4425);
DISPLAY 0.872340 (-2450 4425);
PAINT GREEN (-2450 4425);
DISPLAY INVISIBLE (-2450 4425);
FORCEPROP 2 LAST PATH I116
J 0
(-1675 4575);
DISPLAY 0.680851 (-1675 4575);
DISPLAY INVISIBLE (-1675 4575);
FORCEADD OFFPAGE..1
R 2
(-2325 4375);
FORCEPROP 2 LAST $XR0 167 
J 0
(-2139 4375);
DISPLAY 0.638298 (-2139 4375);
PAINT MONO (-2139 4375);
FORCEPROP 2 LAST CDS_LIB standard
J 0
(-2325 4375);
DISPLAY INVISIBLE (-2325 4375);
FORCEPROP 1 LAST OFFPAGE TRUE
J 2
(-2650 4250);
DISPLAY 0.872340 (-2650 4250);
PAINT GREEN (-2650 4250);
DISPLAY INVISIBLE (-2650 4250);
FORCEPROP 1 LAST COMMENT_BODY TRUE
J 2
(-2450 4275);
DISPLAY 0.872340 (-2450 4275);
PAINT GREEN (-2450 4275);
DISPLAY INVISIBLE (-2450 4275);
FORCEPROP 2 LAST PATH I117
J 0
(-2125 4425);
DISPLAY 0.680851 (-2125 4425);
DISPLAY INVISIBLE (-2125 4425);
FORCEADD OFFPAGE..1
R 2
(-2325 4575);
FORCEPROP 2 LAST $XR0 136 
J 0
(-2139 4575);
DISPLAY 0.638298 (-2139 4575);
PAINT MONO (-2139 4575);
FORCEPROP 2 LAST CDS_LIB standard
J 0
(-2325 4575);
DISPLAY INVISIBLE (-2325 4575);
FORCEPROP 1 LAST OFFPAGE TRUE
J 2
(-2650 4450);
DISPLAY 0.872340 (-2650 4450);
PAINT GREEN (-2650 4450);
DISPLAY INVISIBLE (-2650 4450);
FORCEPROP 1 LAST COMMENT_BODY TRUE
J 2
(-2450 4475);
DISPLAY 0.872340 (-2450 4475);
PAINT GREEN (-2450 4475);
DISPLAY INVISIBLE (-2450 4475);
FORCEPROP 2 LAST PATH I118
J 0
(-2150 4650);
DISPLAY 0.680851 (-2150 4650);
DISPLAY INVISIBLE (-2150 4650);
FORCEADD OFFPAGE..1
R 2
(-2325 4725);
FORCEPROP 2 LAST $XR0 92 
J 0
(-2139 4725);
DISPLAY 0.638298 (-2139 4725);
PAINT MONO (-2139 4725);
FORCEPROP 2 LAST CDS_LIB standard
J 0
(-2325 4725);
DISPLAY INVISIBLE (-2325 4725);
FORCEPROP 1 LAST OFFPAGE TRUE
J 2
(-2650 4600);
DISPLAY 0.872340 (-2650 4600);
PAINT GREEN (-2650 4600);
DISPLAY INVISIBLE (-2650 4600);
FORCEPROP 1 LAST COMMENT_BODY TRUE
J 2
(-2450 4625);
DISPLAY 0.872340 (-2450 4625);
PAINT GREEN (-2450 4625);
DISPLAY INVISIBLE (-2450 4625);
FORCEPROP 2 LAST PATH I119
J 0
(-1675 4775);
DISPLAY 0.680851 (-1675 4775);
DISPLAY INVISIBLE (-1675 4775);
FORCEADD OFFPAGE..1
(-7300 4225);
FORCEPROP 2 LAST $XR0 27 
J 0
(-7521 4225);
DISPLAY 0.638298 (-7521 4225);
PAINT MONO (-7521 4225);
FORCEPROP 2 LAST CDS_LIB standard
J 0
(-7300 4225);
DISPLAY INVISIBLE (-7300 4225);
FORCEPROP 1 LAST OFFPAGE TRUE
J 0
(-6975 4100);
DISPLAY 0.872340 (-6975 4100);
PAINT GREEN (-6975 4100);
DISPLAY INVISIBLE (-6975 4100);
FORCEPROP 1 LAST COMMENT_BODY TRUE
J 0
(-7175 4125);
DISPLAY 0.872340 (-7175 4125);
PAINT GREEN (-7175 4125);
DISPLAY INVISIBLE (-7175 4125);
FORCEPROP 2 LAST PATH I12
J 0
(-7550 4275);
DISPLAY 0.680851 (-7550 4275);
DISPLAY INVISIBLE (-7550 4275);
FORCEADD OFFPAGE..2
(-2325 4825);
FORCEPROP 2 LAST $XR0 193 
J 0
(-2136 4825);
DISPLAY 0.638298 (-2136 4825);
PAINT MONO (-2136 4825);
FORCEPROP 2 LAST CDS_LIB standard
J 0
(-2325 4825);
DISPLAY INVISIBLE (-2325 4825);
FORCEPROP 1 LAST OFFPAGE TRUE
J 0
(-2000 4700);
DISPLAY 0.872340 (-2000 4700);
PAINT GREEN (-2000 4700);
DISPLAY INVISIBLE (-2000 4700);
FORCEPROP 1 LAST COMMENT_BODY TRUE
J 0
(-2370 4730);
DISPLAY 0.872340 (-2370 4730);
PAINT GREEN (-2370 4730);
DISPLAY INVISIBLE (-2370 4730);
FORCEPROP 2 LAST PATH I120
J 0
(-2125 4875);
DISPLAY 0.680851 (-2125 4875);
DISPLAY INVISIBLE (-2125 4875);
FORCEADD OFFPAGE..1
R 2
(-2325 4925);
FORCEPROP 2 LAST $XR0 193 
J 0
(-2139 4925);
DISPLAY 0.638298 (-2139 4925);
PAINT MONO (-2139 4925);
FORCEPROP 2 LAST CDS_LIB standard
J 0
(-2325 4925);
DISPLAY INVISIBLE (-2325 4925);
FORCEPROP 1 LAST OFFPAGE TRUE
J 2
(-2650 4800);
DISPLAY 0.872340 (-2650 4800);
PAINT GREEN (-2650 4800);
DISPLAY INVISIBLE (-2650 4800);
FORCEPROP 1 LAST COMMENT_BODY TRUE
J 2
(-2450 4825);
DISPLAY 0.872340 (-2450 4825);
PAINT GREEN (-2450 4825);
DISPLAY INVISIBLE (-2450 4825);
FORCEPROP 2 LAST PATH I121
J 0
(-2125 4975);
DISPLAY 0.680851 (-2125 4975);
DISPLAY INVISIBLE (-2125 4975);
FORCEADD OFFPAGE..2
(-2325 4975);
FORCEPROP 2 LAST $XR0 207 
J 0
(-2136 4975);
DISPLAY 0.638298 (-2136 4975);
PAINT MONO (-2136 4975);
FORCEPROP 2 LAST CDS_LIB standard
J 0
(-2325 4975);
DISPLAY INVISIBLE (-2325 4975);
FORCEPROP 1 LAST OFFPAGE TRUE
J 0
(-2000 4850);
DISPLAY 0.872340 (-2000 4850);
PAINT GREEN (-2000 4850);
DISPLAY INVISIBLE (-2000 4850);
FORCEPROP 1 LAST COMMENT_BODY TRUE
J 0
(-2370 4880);
DISPLAY 0.872340 (-2370 4880);
PAINT GREEN (-2370 4880);
DISPLAY INVISIBLE (-2370 4880);
FORCEPROP 2 LAST PATH I122
J 0
(-2125 5025);
DISPLAY 0.680851 (-2125 5025);
DISPLAY INVISIBLE (-2125 5025);
FORCEADD OFFPAGE..1
R 2
(-2325 5025);
FORCEPROP 2 LAST $XR0 167 
J 0
(-2139 5025);
DISPLAY 0.638298 (-2139 5025);
PAINT MONO (-2139 5025);
FORCEPROP 2 LAST CDS_LIB standard
J 0
(-2325 5025);
DISPLAY INVISIBLE (-2325 5025);
FORCEPROP 1 LAST OFFPAGE TRUE
J 2
(-2650 4900);
DISPLAY 0.872340 (-2650 4900);
PAINT GREEN (-2650 4900);
DISPLAY INVISIBLE (-2650 4900);
FORCEPROP 1 LAST COMMENT_BODY TRUE
J 2
(-2450 4925);
DISPLAY 0.872340 (-2450 4925);
PAINT GREEN (-2450 4925);
DISPLAY INVISIBLE (-2450 4925);
FORCEPROP 2 LAST PATH I123
J 0
(-2125 5075);
DISPLAY 0.680851 (-2125 5075);
DISPLAY INVISIBLE (-2125 5075);
FORCEADD OFFPAGE..1
R 2
(-2325 4875);
FORCEPROP 2 LAST $XR0 193 
J 0
(-2139 4875);
DISPLAY 0.638298 (-2139 4875);
PAINT MONO (-2139 4875);
FORCEPROP 2 LAST CDS_LIB standard
J 0
(-2325 4875);
DISPLAY INVISIBLE (-2325 4875);
FORCEPROP 1 LAST OFFPAGE TRUE
J 2
(-2650 4750);
DISPLAY 0.872340 (-2650 4750);
PAINT GREEN (-2650 4750);
DISPLAY INVISIBLE (-2650 4750);
FORCEPROP 1 LAST COMMENT_BODY TRUE
J 2
(-2450 4775);
DISPLAY 0.872340 (-2450 4775);
PAINT GREEN (-2450 4775);
DISPLAY INVISIBLE (-2450 4775);
FORCEPROP 2 LAST PATH I124
J 0
(-2125 4925);
DISPLAY 0.680851 (-2125 4925);
DISPLAY INVISIBLE (-2125 4925);
FORCEADD OFFPAGE..2
(-2325 5075);
FORCEPROP 2 LAST $XR0 217 
J 0
(-2136 5075);
DISPLAY 0.638298 (-2136 5075);
PAINT MONO (-2136 5075);
FORCEPROP 2 LAST CDS_LIB standard
J 0
(-2325 5075);
DISPLAY INVISIBLE (-2325 5075);
FORCEPROP 1 LAST OFFPAGE TRUE
J 0
(-2000 4950);
DISPLAY 0.872340 (-2000 4950);
PAINT GREEN (-2000 4950);
DISPLAY INVISIBLE (-2000 4950);
FORCEPROP 1 LAST COMMENT_BODY TRUE
J 0
(-2370 4980);
DISPLAY 0.872340 (-2370 4980);
PAINT GREEN (-2370 4980);
DISPLAY INVISIBLE (-2370 4980);
FORCEPROP 2 LAST PATH I125
J 0
(-2125 5125);
DISPLAY 0.680851 (-2125 5125);
DISPLAY INVISIBLE (-2125 5125);
FORCEADD OFFPAGE..2
(-2150 5575);
FORCEPROP 2 LAST $XR0 28 
J 0
(-1961 5575);
DISPLAY 0.638298 (-1961 5575);
PAINT MONO (-1961 5575);
FORCEPROP 2 LAST CDS_LIB standard
J 0
(-2150 5575);
DISPLAY INVISIBLE (-2150 5575);
FORCEPROP 1 LAST OFFPAGE TRUE
J 0
(-1825 5450);
DISPLAY 0.872340 (-1825 5450);
PAINT GREEN (-1825 5450);
DISPLAY INVISIBLE (-1825 5450);
FORCEPROP 1 LAST COMMENT_BODY TRUE
J 0
(-2195 5480);
DISPLAY 0.872340 (-2195 5480);
PAINT GREEN (-2195 5480);
DISPLAY INVISIBLE (-2195 5480);
FORCEPROP 2 LAST PATH I129
J 0
(-1950 5625);
DISPLAY 0.680851 (-1950 5625);
DISPLAY INVISIBLE (-1950 5625);
FORCEADD OFFPAGE..1
(-7300 4325);
FORCEPROP 2 LAST $XR0 27 
J 0
(-7521 4325);
DISPLAY 0.638298 (-7521 4325);
PAINT MONO (-7521 4325);
FORCEPROP 2 LAST CDS_LIB standard
J 0
(-7300 4325);
DISPLAY INVISIBLE (-7300 4325);
FORCEPROP 1 LAST OFFPAGE TRUE
J 0
(-6975 4200);
DISPLAY 0.872340 (-6975 4200);
PAINT GREEN (-6975 4200);
DISPLAY INVISIBLE (-6975 4200);
FORCEPROP 1 LAST COMMENT_BODY TRUE
J 0
(-7175 4225);
DISPLAY 0.872340 (-7175 4225);
PAINT GREEN (-7175 4225);
DISPLAY INVISIBLE (-7175 4225);
FORCEPROP 2 LAST PATH I13
J 0
(-7500 4375);
DISPLAY 0.680851 (-7500 4375);
DISPLAY INVISIBLE (-7500 4375);
FORCEADD OFFPAGE..2
(-2150 5525);
FORCEPROP 2 LAST $XR0 27 
J 0
(-1961 5525);
DISPLAY 0.638298 (-1961 5525);
PAINT MONO (-1961 5525);
FORCEPROP 2 LAST CDS_LIB standard
J 0
(-2150 5525);
DISPLAY INVISIBLE (-2150 5525);
FORCEPROP 1 LAST OFFPAGE TRUE
J 0
(-1825 5400);
DISPLAY 0.872340 (-1825 5400);
PAINT GREEN (-1825 5400);
DISPLAY INVISIBLE (-1825 5400);
FORCEPROP 1 LAST COMMENT_BODY TRUE
J 0
(-2195 5430);
DISPLAY 0.872340 (-2195 5430);
PAINT GREEN (-2195 5430);
DISPLAY INVISIBLE (-2195 5430);
FORCEPROP 2 LAST PATH I130
J 0
(-1950 5575);
DISPLAY 0.680851 (-1950 5575);
DISPLAY INVISIBLE (-1950 5575);
FORCEADD OFFPAGE..1
R 2
(-2150 5675);
FORCEPROP 2 LAST $XR1 54 
J 0
(-1874 5675);
DISPLAY 0.638298 (-1874 5675);
PAINT MONO (-1874 5675);
FORCEPROP 2 LAST $XR0 27 
J 0
(-1964 5675);
DISPLAY 0.638298 (-1964 5675);
PAINT MONO (-1964 5675);
FORCEPROP 2 LAST CDS_LIB standard
J 0
(-2150 5675);
DISPLAY INVISIBLE (-2150 5675);
FORCEPROP 1 LAST OFFPAGE TRUE
J 2
(-2475 5550);
DISPLAY 0.872340 (-2475 5550);
PAINT GREEN (-2475 5550);
DISPLAY INVISIBLE (-2475 5550);
FORCEPROP 1 LAST COMMENT_BODY TRUE
J 2
(-2275 5575);
DISPLAY 0.872340 (-2275 5575);
PAINT GREEN (-2275 5575);
DISPLAY INVISIBLE (-2275 5575);
FORCEPROP 2 LAST PATH I131
J 0
(-1850 5725);
DISPLAY 0.680851 (-1850 5725);
DISPLAY INVISIBLE (-1850 5725);
FORCEADD OFFPAGE..2
(-2150 5725);
FORCEPROP 2 LAST $XR0 27 
J 0
(-1961 5725);
DISPLAY 0.638298 (-1961 5725);
PAINT MONO (-1961 5725);
FORCEPROP 2 LAST CDS_LIB standard
J 0
(-2150 5725);
DISPLAY INVISIBLE (-2150 5725);
FORCEPROP 1 LAST OFFPAGE TRUE
J 0
(-1825 5600);
DISPLAY 0.872340 (-1825 5600);
PAINT GREEN (-1825 5600);
DISPLAY INVISIBLE (-1825 5600);
FORCEPROP 1 LAST COMMENT_BODY TRUE
J 0
(-2195 5630);
DISPLAY 0.872340 (-2195 5630);
PAINT GREEN (-2195 5630);
DISPLAY INVISIBLE (-2195 5630);
FORCEPROP 2 LAST PATH I132
J 0
(-1950 5775);
DISPLAY 0.680851 (-1950 5775);
DISPLAY INVISIBLE (-1950 5775);
FORCEADD OFFPAGE..2
(-2150 5775);
FORCEPROP 2 LAST $XR0 27 
J 0
(-1961 5775);
DISPLAY 0.638298 (-1961 5775);
PAINT MONO (-1961 5775);
FORCEPROP 2 LAST CDS_LIB standard
J 0
(-2150 5775);
DISPLAY INVISIBLE (-2150 5775);
FORCEPROP 1 LAST OFFPAGE TRUE
J 0
(-1825 5650);
DISPLAY 0.872340 (-1825 5650);
PAINT GREEN (-1825 5650);
DISPLAY INVISIBLE (-1825 5650);
FORCEPROP 1 LAST COMMENT_BODY TRUE
J 0
(-2195 5680);
DISPLAY 0.872340 (-2195 5680);
PAINT GREEN (-2195 5680);
DISPLAY INVISIBLE (-2195 5680);
FORCEPROP 2 LAST PATH I133
J 0
(-1950 5825);
DISPLAY 0.680851 (-1950 5825);
DISPLAY INVISIBLE (-1950 5825);
FORCEADD OFFPAGE..2
(-2150 5825);
FORCEPROP 2 LAST $XR0 54 
J 0
(-1961 5825);
DISPLAY 0.638298 (-1961 5825);
PAINT MONO (-1961 5825);
FORCEPROP 2 LAST CDS_LIB standard
J 0
(-2150 5825);
DISPLAY INVISIBLE (-2150 5825);
FORCEPROP 1 LAST OFFPAGE TRUE
J 0
(-1825 5700);
DISPLAY 0.872340 (-1825 5700);
PAINT GREEN (-1825 5700);
DISPLAY INVISIBLE (-1825 5700);
FORCEPROP 1 LAST COMMENT_BODY TRUE
J 0
(-2195 5730);
DISPLAY 0.872340 (-2195 5730);
PAINT GREEN (-2195 5730);
DISPLAY INVISIBLE (-2195 5730);
FORCEPROP 2 LAST PATH I134
J 0
(-1950 5875);
DISPLAY 0.680851 (-1950 5875);
DISPLAY INVISIBLE (-1950 5875);
FORCEADD OFFPAGE..1
R 2
(-2150 5925);
FORCEPROP 2 LAST $XR0 27 
J 0
(-1964 5925);
DISPLAY 0.638298 (-1964 5925);
PAINT MONO (-1964 5925);
FORCEPROP 2 LAST CDS_LIB standard
J 0
(-2150 5925);
DISPLAY INVISIBLE (-2150 5925);
FORCEPROP 1 LAST OFFPAGE TRUE
J 2
(-2475 5800);
DISPLAY 0.872340 (-2475 5800);
PAINT GREEN (-2475 5800);
DISPLAY INVISIBLE (-2475 5800);
FORCEPROP 1 LAST COMMENT_BODY TRUE
J 2
(-2275 5825);
DISPLAY 0.872340 (-2275 5825);
PAINT GREEN (-2275 5825);
DISPLAY INVISIBLE (-2275 5825);
FORCEPROP 2 LAST PATH I135
J 0
(-1950 5975);
DISPLAY 0.680851 (-1950 5975);
DISPLAY INVISIBLE (-1950 5975);
FORCEADD OFFPAGE..1
R 2
(-2150 5975);
FORCEPROP 2 LAST $XR0 207 
J 0
(-1964 5975);
DISPLAY 0.638298 (-1964 5975);
PAINT MONO (-1964 5975);
FORCEPROP 2 LAST CDS_LIB standard
J 2
(-2150 5975);
DISPLAY INVISIBLE (-2150 5975);
FORCEPROP 1 LAST OFFPAGE TRUE
J 2
(-2475 5850);
DISPLAY 0.872340 (-2475 5850);
PAINT GREEN (-2475 5850);
DISPLAY INVISIBLE (-2475 5850);
FORCEPROP 1 LAST COMMENT_BODY TRUE
J 2
(-2275 5875);
DISPLAY 0.872340 (-2275 5875);
PAINT GREEN (-2275 5875);
DISPLAY INVISIBLE (-2275 5875);
FORCEPROP 2 LAST PATH I136
J 0
(-1950 6025);
DISPLAY 0.680851 (-1950 6025);
DISPLAY INVISIBLE (-1950 6025);
FORCEADD OFFPAGE..1
R 2
(-2150 6025);
FORCEPROP 2 LAST $XR0 224 
J 0
(-1964 6025);
DISPLAY 0.638298 (-1964 6025);
PAINT MONO (-1964 6025);
FORCEPROP 2 LAST CDS_LIB standard
J 0
(-2150 6025);
DISPLAY INVISIBLE (-2150 6025);
FORCEPROP 1 LAST OFFPAGE TRUE
J 2
(-2475 5900);
DISPLAY 0.872340 (-2475 5900);
PAINT GREEN (-2475 5900);
DISPLAY INVISIBLE (-2475 5900);
FORCEPROP 1 LAST COMMENT_BODY TRUE
J 2
(-2275 5925);
DISPLAY 0.872340 (-2275 5925);
PAINT GREEN (-2275 5925);
DISPLAY INVISIBLE (-2275 5925);
FORCEPROP 2 LAST PATH I137
J 0
(-1950 6075);
DISPLAY 0.680851 (-1950 6075);
DISPLAY INVISIBLE (-1950 6075);
FORCEADD OFFPAGE..2
(-2150 6075);
FORCEPROP 2 LAST $XR0 54 
J 0
(-1961 6075);
DISPLAY 0.638298 (-1961 6075);
PAINT MONO (-1961 6075);
FORCEPROP 2 LAST CDS_LIB standard
J 0
(-2150 6075);
DISPLAY INVISIBLE (-2150 6075);
FORCEPROP 1 LAST OFFPAGE TRUE
J 0
(-1825 5950);
DISPLAY 0.872340 (-1825 5950);
PAINT GREEN (-1825 5950);
DISPLAY INVISIBLE (-1825 5950);
FORCEPROP 1 LAST COMMENT_BODY TRUE
J 0
(-2195 5980);
DISPLAY 0.872340 (-2195 5980);
PAINT GREEN (-2195 5980);
DISPLAY INVISIBLE (-2195 5980);
FORCEPROP 2 LAST PATH I138
J 0
(-1950 6125);
DISPLAY 0.680851 (-1950 6125);
DISPLAY INVISIBLE (-1950 6125);
FORCEADD OFFPAGE..1
R 2
(-2150 6125);
FORCEPROP 2 LAST $XR0 210 
J 0
(-1964 6125);
DISPLAY 0.638298 (-1964 6125);
PAINT MONO (-1964 6125);
FORCEPROP 2 LAST CDS_LIB standard
J 2
(-2150 6125);
DISPLAY INVISIBLE (-2150 6125);
FORCEPROP 1 LAST OFFPAGE TRUE
J 2
(-2475 6000);
DISPLAY 0.872340 (-2475 6000);
PAINT GREEN (-2475 6000);
DISPLAY INVISIBLE (-2475 6000);
FORCEPROP 1 LAST COMMENT_BODY TRUE
J 2
(-2275 6025);
DISPLAY 0.872340 (-2275 6025);
PAINT GREEN (-2275 6025);
DISPLAY INVISIBLE (-2275 6025);
FORCEPROP 2 LAST PATH I139
J 0
(-1950 6175);
DISPLAY 0.680851 (-1950 6175);
DISPLAY INVISIBLE (-1950 6175);
FORCEADD OFFPAGE..1
(-7300 4525);
FORCEPROP 2 LAST $XR0 54 
J 0
(-7521 4525);
DISPLAY 0.638298 (-7521 4525);
PAINT MONO (-7521 4525);
FORCEPROP 2 LAST CDS_LIB standard
J 0
(-7300 4525);
DISPLAY INVISIBLE (-7300 4525);
FORCEPROP 1 LAST OFFPAGE TRUE
J 0
(-6975 4400);
DISPLAY 0.872340 (-6975 4400);
PAINT GREEN (-6975 4400);
DISPLAY INVISIBLE (-6975 4400);
FORCEPROP 1 LAST COMMENT_BODY TRUE
J 0
(-7175 4425);
DISPLAY 0.872340 (-7175 4425);
PAINT GREEN (-7175 4425);
DISPLAY INVISIBLE (-7175 4425);
FORCEPROP 2 LAST PATH I14
J 0
(-7500 4575);
DISPLAY 0.680851 (-7500 4575);
DISPLAY INVISIBLE (-7500 4575);
FORCEADD Q_RES..1
(-3250 6125);
FORCEPROP 1 LAST LOCATION R284
J 0
(-3125 6125);
DISPLAY 0.489362 (-3125 6125);
PAINT SKYBLUE (-3125 6125);
FORCEPROP 0 LAST $SEC 1
J 0
(-3125 6175);
DISPLAY 0.680851 (-3125 6175);
PAINT MONO (-3125 6175);
DISPLAY INVISIBLE (-3125 6175);
FORCEPROP 0 LAST CDS_SEC 1
J 0
(-3125 6175);
DISPLAY 1.021277 (-3125 6175);
DISPLAY INVISIBLE (-3125 6175);
FORCEPROP 1 LASTPIN (-3350 6125) $PN 1
J 0
(-3338 6137);
DISPLAY 0.489362 (-3338 6137);
PAINT MONO (-3338 6137);
FORCEPROP 1 LASTPIN (-3150 6125) $PN 2
J 0
(-3188 6137);
DISPLAY 0.489362 (-3188 6137);
PAINT MONO (-3188 6137);
FORCEPROP 1 LAST VALUE 0
J 2
(-3375 6125);
DISPLAY 0.489362 (-3375 6125);
PAINT SKYBLUE (-3375 6125);
FORCEPROP 2 LAST BOM_COST MEM
J 2
(-3225 6275);
DISPLAY 0.744681 (-3225 6275);
PAINT WHITE (-3225 6275);
DISPLAY INVISIBLE (-3225 6275);
FORCEPROP 2 LAST CDS_LIB pure_quanta
J 2
(-3250 6125);
DISPLAY INVISIBLE (-3250 6125);
FORCEPROP 1 LAST WATTAGE 1/16W
J 2
(-3325 6050);
DISPLAY 0.489362 (-3325 6050);
PAINT SKYBLUE (-3325 6050);
DISPLAY INVISIBLE (-3325 6050);
FORCEPROP 1 LAST MATERIAL CHIP
J 2
(-3075 6100);
DISPLAY 0.489362 (-3075 6100);
PAINT SKYBLUE (-3075 6100);
DISPLAY INVISIBLE (-3075 6100);
FORCEPROP 1 LAST TOLERANCE 5%
J 0
(-3375 6100);
DISPLAY 0.489362 (-3375 6100);
PAINT SKYBLUE (-3375 6100);
DISPLAY INVISIBLE (-3375 6100);
FORCEPROP 1 LAST PACK_TYPE 0402LF
J 2
(-3075 6050);
DISPLAY 0.489362 (-3075 6050);
PAINT SKYBLUE (-3075 6050);
DISPLAY INVISIBLE (-3075 6050);
FORCEPROP 1 LAST PATH I140
J 0
(-3300 6275);
DISPLAY 0.978723 (-3300 6275);
PAINT WHITE (-3300 6275);
DISPLAY INVISIBLE (-3300 6275);
FORCEPROP 1 LAST PART_NUMBER CS00002JB13
J 2
(-3150 6175);
DISPLAY 0.489362 (-3150 6175);
PAINT SKYBLUE (-3150 6175);
DISPLAY INVISIBLE (-3150 6175);
FORCEADD LCMXO3LF9400C5BG484C..5
(-2325 1525);
FORCEPROP 1 LAST LOCATION U18
J 0
(-2722 2816);
DISPLAY 0.723404 (-2722 2816);
PAINT GREEN (-2722 2816);
FORCEPROP 2 LAST SEC 5
J 0
(-2700 2950);
DISPLAY 0.680851 (-2700 2950);
PAINT MONO (-2700 2950);
DISPLAY INVISIBLE (-2700 2950);
FORCEPROP 2 LASTPIN (-2875 2475) $PN K10
J 2
(-2885 2485);
DISPLAY 0.680851 (-2885 2485);
PAINT MONO (-2885 2485);
FORCEPROP 2 LASTPIN (-2875 2425) $PN K11
J 2
(-2885 2435);
DISPLAY 0.680851 (-2885 2435);
PAINT MONO (-2885 2435);
FORCEPROP 2 LASTPIN (-2875 2375) $PN K12
J 2
(-2885 2385);
DISPLAY 0.680851 (-2885 2385);
PAINT MONO (-2885 2385);
FORCEPROP 2 LASTPIN (-2875 2325) $PN K13
J 2
(-2885 2335);
DISPLAY 0.680851 (-2885 2335);
PAINT MONO (-2885 2335);
FORCEPROP 2 LASTPIN (-2875 2275) $PN L11
J 2
(-2885 2285);
DISPLAY 0.680851 (-2885 2285);
PAINT MONO (-2885 2285);
FORCEPROP 2 LASTPIN (-2875 2225) $PN L12
J 2
(-2885 2235);
DISPLAY 0.680851 (-2885 2235);
PAINT MONO (-2885 2235);
FORCEPROP 2 LASTPIN (-2875 2175) $PN M11
J 2
(-2885 2185);
DISPLAY 0.680851 (-2885 2185);
PAINT MONO (-2885 2185);
FORCEPROP 2 LASTPIN (-2875 2125) $PN M12
J 2
(-2885 2135);
DISPLAY 0.680851 (-2885 2135);
PAINT MONO (-2885 2135);
FORCEPROP 2 LASTPIN (-2875 2075) $PN N10
J 2
(-2885 2085);
DISPLAY 0.680851 (-2885 2085);
PAINT MONO (-2885 2085);
FORCEPROP 2 LASTPIN (-2875 2025) $PN N11
J 2
(-2885 2035);
DISPLAY 0.680851 (-2885 2035);
PAINT MONO (-2885 2035);
FORCEPROP 2 LASTPIN (-2875 1975) $PN N12
J 2
(-2885 1985);
DISPLAY 0.680851 (-2885 1985);
PAINT MONO (-2885 1985);
FORCEPROP 2 LASTPIN (-2875 1925) $PN N13
J 2
(-2885 1935);
DISPLAY 0.680851 (-2885 1935);
PAINT MONO (-2885 1935);
FORCEPROP 2 LASTPIN (-1775 1075) $PN C7
J 0
(-1765 1085);
DISPLAY 0.680851 (-1765 1085);
PAINT MONO (-1765 1085);
FORCEPROP 2 LASTPIN (-1775 1025) $PN C12
J 0
(-1765 1035);
DISPLAY 0.680851 (-1765 1035);
PAINT MONO (-1765 1035);
FORCEPROP 2 LASTPIN (-1775 975) $PN C16
J 0
(-1765 985);
DISPLAY 0.680851 (-1765 985);
PAINT MONO (-1765 985);
FORCEPROP 2 LASTPIN (-1775 925) $PN G10
J 0
(-1765 935);
DISPLAY 0.680851 (-1765 935);
PAINT MONO (-1765 935);
FORCEPROP 2 LASTPIN (-1775 875) $PN G13
J 0
(-1765 885);
DISPLAY 0.680851 (-1765 885);
PAINT MONO (-1765 885);
FORCEPROP 2 LASTPIN (-1775 825) $PN H9
J 0
(-1765 835);
DISPLAY 0.680851 (-1765 835);
PAINT MONO (-1765 835);
FORCEPROP 2 LASTPIN (-1775 775) $PN H11
J 0
(-1765 785);
DISPLAY 0.680851 (-1765 785);
PAINT MONO (-1765 785);
FORCEPROP 2 LASTPIN (-1775 725) $PN H12
J 0
(-1765 735);
DISPLAY 0.680851 (-1765 735);
PAINT MONO (-1765 735);
FORCEPROP 2 LASTPIN (-1775 675) $PN H14
J 0
(-1765 685);
DISPLAY 0.680851 (-1765 685);
PAINT MONO (-1765 685);
FORCEPROP 2 LASTPIN (-1775 1775) $PN F20
J 0
(-1765 1785);
DISPLAY 0.680851 (-1765 1785);
PAINT MONO (-1765 1785);
FORCEPROP 2 LASTPIN (-1775 1725) $PN J15
J 0
(-1765 1735);
DISPLAY 0.680851 (-1765 1735);
PAINT MONO (-1765 1735);
FORCEPROP 2 LASTPIN (-1775 1675) $PN K15
J 0
(-1765 1685);
DISPLAY 0.680851 (-1765 1685);
PAINT MONO (-1765 1685);
FORCEPROP 2 LASTPIN (-1775 1625) $PN L15
J 0
(-1765 1635);
DISPLAY 0.680851 (-1765 1635);
PAINT MONO (-1765 1635);
FORCEPROP 2 LASTPIN (-1775 1575) $PN M15
J 0
(-1765 1585);
DISPLAY 0.680851 (-1765 1585);
PAINT MONO (-1765 1585);
FORCEPROP 2 LASTPIN (-1775 1525) $PN M18
J 0
(-1765 1535);
DISPLAY 0.680851 (-1765 1535);
PAINT MONO (-1765 1535);
FORCEPROP 2 LASTPIN (-1775 1475) $PN N15
J 0
(-1765 1485);
DISPLAY 0.680851 (-1765 1485);
PAINT MONO (-1765 1485);
FORCEPROP 2 LASTPIN (-1775 1425) $PN P15
J 0
(-1765 1435);
DISPLAY 0.680851 (-1765 1435);
PAINT MONO (-1765 1435);
FORCEPROP 2 LASTPIN (-1775 1375) $PN V20
J 0
(-1765 1385);
DISPLAY 0.680851 (-1765 1385);
PAINT MONO (-1765 1385);
FORCEPROP 2 LASTPIN (-2875 1075) $PN R9
J 2
(-2885 1085);
DISPLAY 0.680851 (-2885 1085);
PAINT MONO (-2885 1085);
FORCEPROP 2 LASTPIN (-2875 1025) $PN R10
J 2
(-2885 1035);
DISPLAY 0.680851 (-2885 1035);
PAINT MONO (-2885 1035);
FORCEPROP 2 LASTPIN (-2875 975) $PN R11
J 2
(-2885 985);
DISPLAY 0.680851 (-2885 985);
PAINT MONO (-2885 985);
FORCEPROP 2 LASTPIN (-2875 925) $PN R12
J 2
(-2885 935);
DISPLAY 0.680851 (-2885 935);
PAINT MONO (-2885 935);
FORCEPROP 2 LASTPIN (-2875 875) $PN R13
J 2
(-2885 885);
DISPLAY 0.680851 (-2885 885);
PAINT MONO (-2885 885);
FORCEPROP 2 LASTPIN (-2875 825) $PN R14
J 2
(-2885 835);
DISPLAY 0.680851 (-2885 835);
PAINT MONO (-2885 835);
FORCEPROP 2 LASTPIN (-2875 775) $PN W7
J 2
(-2885 785);
DISPLAY 0.680851 (-2885 785);
PAINT MONO (-2885 785);
FORCEPROP 2 LASTPIN (-2875 725) $PN W11
J 2
(-2885 735);
DISPLAY 0.680851 (-2885 735);
PAINT MONO (-2885 735);
FORCEPROP 2 LASTPIN (-2875 675) $PN W16
J 2
(-2885 685);
DISPLAY 0.680851 (-2885 685);
PAINT MONO (-2885 685);
FORCEPROP 2 LASTPIN (-2875 1275) $PN N8
J 2
(-2885 1285);
DISPLAY 0.680851 (-2885 1285);
PAINT MONO (-2885 1285);
FORCEPROP 2 LASTPIN (-2875 1225) $PN P8
J 2
(-2885 1235);
DISPLAY 0.680851 (-2885 1235);
PAINT MONO (-2885 1235);
FORCEPROP 2 LASTPIN (-2875 1175) $PN V3
J 2
(-2885 1185);
DISPLAY 0.680851 (-2885 1185);
PAINT MONO (-2885 1185);
FORCEPROP 2 LASTPIN (-2875 1575) $PN L8
J 2
(-2885 1585);
DISPLAY 0.680851 (-2885 1585);
PAINT MONO (-2885 1585);
FORCEPROP 2 LASTPIN (-2875 1525) $PN M8
J 2
(-2885 1535);
DISPLAY 0.680851 (-2885 1535);
PAINT MONO (-2885 1535);
FORCEPROP 2 LASTPIN (-2875 1475) $PN M3
J 2
(-2885 1485);
DISPLAY 0.680851 (-2885 1485);
PAINT MONO (-2885 1485);
FORCEPROP 2 LASTPIN (-2875 1775) $PN F3
J 2
(-2885 1785);
DISPLAY 0.680851 (-2885 1785);
PAINT MONO (-2885 1785);
FORCEPROP 2 LASTPIN (-2875 1725) $PN J8
J 2
(-2885 1735);
DISPLAY 0.680851 (-2885 1735);
PAINT MONO (-2885 1735);
FORCEPROP 2 LASTPIN (-2875 1675) $PN K8
J 2
(-2885 1685);
DISPLAY 0.680851 (-2885 1685);
PAINT MONO (-2885 1685);
FORCEPROP 1 LAST MATERIAL IC
J 0
(-2722 2542);
DISPLAY 0.723404 (-2722 2542);
PAINT GREEN (-2722 2542);
FORCEPROP 2 LAST VALUE LCMXO3LF-9400C-5BG484C
J 0
(-2715 2860);
DISPLAY 0.489362 (-2715 2860);
PAINT SKYBLUE (-2715 2860);
FORCEPROP 2 LAST PART_TYPE SMLF
J 0
(-2715 2905);
DISPLAY 0.680851 (-2715 2905);
FORCEPROP 2 LAST CDS_LIB pure_quanta
J 0
(-2325 1525);
DISPLAY INVISIBLE (-2325 1525);
FORCEPROP 1 LAST NEEDS_NO_SIZE TRUE
J 0
(-2325 1525);
DISPLAY 0.723404 (-2325 1525);
PAINT GREEN (-2325 1525);
DISPLAY INVISIBLE (-2325 1525);
FORCEPROP 1 LAST CDS_LMAN_SYM_OUTLINE -400,1000,400,-1000
J 0
(-2325 1525);
DISPLAY 0.468085 (-2325 1525);
PAINT GREEN (-2325 1525);
DISPLAY INVISIBLE (-2325 1525);
FORCEPROP 2 LAST SEC_TYPE 
J 0
(-2700 2950);
DISPLAY 0.680851 (-2700 2950);
DISPLAY INVISIBLE (-2700 2950);
FORCEPROP 1 LAST PATH I141
J 0
(-2325 1525);
DISPLAY 0.723404 (-2325 1525);
PAINT GREEN (-2325 1525);
DISPLAY INVISIBLE (-2325 1525);
FORCEPROP 1 LAST PART_NUMBER AJ094000T08
J 0
(-2722 2669);
DISPLAY 0.723404 (-2722 2669);
PAINT GREEN (-2722 2669);
DISPLAY INVISIBLE (-2722 2669);
FORCEADD UNIVERSAL_POWER..1
R 2
(-3175 2600);
FORCEPROP 3 LASTPIN (-3175 2550) SIG_NAME P3V3_AUX\g
J 0
(-3165 2560);
DISPLAY 0.659574 (-3165 2560);
PAINT MONO (-3165 2560);
DISPLAY INVISIBLE (-3165 2560);
FORCEPROP 1 LAST HDL_POWER P3V3_AUX
J 1
(-3175 2650);
DISPLAY 0.489362 (-3175 2650);
PAINT GREEN (-3175 2650);
FORCEPROP 2 LAST CDS_LIB pure_quanta_power
J 0
(-3175 2600);
DISPLAY INVISIBLE (-3175 2600);
FORCEPROP 1 LAST PATH I142
J 2
(-3225 2625);
DISPLAY 0.872340 (-3225 2625);
PAINT AQUA (-3225 2625);
DISPLAY INVISIBLE (-3225 2625);
FORCEADD LCMXO3LF9400C5BG484C..1
(-4850 4775);
FORCEPROP 1 LAST LOCATION U18
J 0
(-5350 6375);
DISPLAY 0.723404 (-5350 6375);
PAINT GREEN (-5350 6375);
FORCEPROP 2 LAST SEC 1
J 0
(-5325 6500);
DISPLAY 0.680851 (-5325 6500);
PAINT MONO (-5325 6500);
DISPLAY INVISIBLE (-5325 6500);
FORCEPROP 2 LASTPIN (-5500 6125) $PN D3
J 2
(-5510 6135);
DISPLAY 0.680851 (-5510 6135);
PAINT MONO (-5510 6135);
FORCEPROP 2 LASTPIN (-5500 6075) $PN D4
J 2
(-5510 6085);
DISPLAY 0.680851 (-5510 6085);
PAINT MONO (-5510 6085);
FORCEPROP 2 LASTPIN (-5500 6025) $PN F6
J 2
(-5510 6035);
DISPLAY 0.680851 (-5510 6035);
PAINT MONO (-5510 6035);
FORCEPROP 2 LASTPIN (-5500 5975) $PN G7
J 2
(-5510 5985);
DISPLAY 0.680851 (-5510 5985);
PAINT MONO (-5510 5985);
FORCEPROP 2 LASTPIN (-5500 5925) $PN E4
J 2
(-5510 5935);
DISPLAY 0.680851 (-5510 5935);
PAINT MONO (-5510 5935);
FORCEPROP 2 LASTPIN (-5500 5875) $PN F5
J 2
(-5510 5885);
DISPLAY 0.680851 (-5510 5885);
PAINT MONO (-5510 5885);
FORCEPROP 2 LASTPIN (-5500 5825) $PN G6
J 2
(-5510 5835);
DISPLAY 0.680851 (-5510 5835);
PAINT MONO (-5510 5835);
FORCEPROP 2 LASTPIN (-5500 5775) $PN H7
J 2
(-5510 5785);
DISPLAY 0.680851 (-5510 5785);
PAINT MONO (-5510 5785);
FORCEPROP 2 LASTPIN (-5500 5725) $PN C1
J 2
(-5510 5735);
DISPLAY 0.680851 (-5510 5735);
PAINT MONO (-5510 5735);
FORCEPROP 2 LASTPIN (-5500 5675) $PN D2
J 2
(-5510 5685);
DISPLAY 0.680851 (-5510 5685);
PAINT MONO (-5510 5685);
FORCEPROP 2 LASTPIN (-5500 5625) $PN G5
J 2
(-5510 5635);
DISPLAY 0.680851 (-5510 5635);
PAINT MONO (-5510 5635);
FORCEPROP 2 LASTPIN (-5500 5575) $PN H6
J 2
(-5510 5585);
DISPLAY 0.680851 (-5510 5585);
PAINT MONO (-5510 5585);
FORCEPROP 2 LASTPIN (-5500 5525) $PN D1
J 2
(-5510 5535);
DISPLAY 0.680851 (-5510 5535);
PAINT MONO (-5510 5535);
FORCEPROP 2 LASTPIN (-5500 5475) $PN E2
J 2
(-5510 5485);
DISPLAY 0.680851 (-5510 5485);
PAINT MONO (-5510 5485);
FORCEPROP 2 LASTPIN (-5500 5425) $PN E3
J 2
(-5510 5435);
DISPLAY 0.680851 (-5510 5435);
PAINT MONO (-5510 5435);
FORCEPROP 2 LASTPIN (-5500 5375) $PN F4
J 2
(-5510 5385);
DISPLAY 0.680851 (-5510 5385);
PAINT MONO (-5510 5385);
FORCEPROP 2 LASTPIN (-5500 5325) $PN E1
J 2
(-5510 5335);
DISPLAY 0.680851 (-5510 5335);
PAINT MONO (-5510 5335);
FORCEPROP 2 LASTPIN (-5500 5275) $PN F1
J 2
(-5510 5285);
DISPLAY 0.680851 (-5510 5285);
PAINT MONO (-5510 5285);
FORCEPROP 2 LASTPIN (-5500 5225) $PN G3
J 2
(-5510 5235);
DISPLAY 0.680851 (-5510 5235);
PAINT MONO (-5510 5235);
FORCEPROP 2 LASTPIN (-5500 5175) $PN G4
J 2
(-5510 5185);
DISPLAY 0.680851 (-5510 5185);
PAINT MONO (-5510 5185);
FORCEPROP 2 LASTPIN (-4200 6125) $PN G2
J 0
(-4190 6135);
DISPLAY 0.680851 (-4190 6135);
PAINT MONO (-4190 6135);
FORCEPROP 2 LASTPIN (-4200 6075) $PN G1
J 0
(-4190 6085);
DISPLAY 0.680851 (-4190 6085);
PAINT MONO (-4190 6085);
FORCEPROP 2 LASTPIN (-4200 6025) $PN H4
J 0
(-4190 6035);
DISPLAY 0.680851 (-4190 6035);
PAINT MONO (-4190 6035);
FORCEPROP 2 LASTPIN (-4200 5975) $PN H3
J 0
(-4190 5985);
DISPLAY 0.680851 (-4190 5985);
PAINT MONO (-4190 5985);
FORCEPROP 2 LASTPIN (-4200 5925) $PN H2
J 0
(-4190 5935);
DISPLAY 0.680851 (-4190 5935);
PAINT MONO (-4190 5935);
FORCEPROP 2 LASTPIN (-4200 5875) $PN H1
J 0
(-4190 5885);
DISPLAY 0.680851 (-4190 5885);
PAINT MONO (-4190 5885);
FORCEPROP 2 LASTPIN (-4200 5825) $PN J7
J 0
(-4190 5835);
DISPLAY 0.680851 (-4190 5835);
PAINT MONO (-4190 5835);
FORCEPROP 2 LASTPIN (-4200 5775) $PN J6
J 0
(-4190 5785);
DISPLAY 0.680851 (-4190 5785);
PAINT MONO (-4190 5785);
FORCEPROP 2 LASTPIN (-4200 5725) $PN H5
J 0
(-4190 5735);
DISPLAY 0.680851 (-4190 5735);
PAINT MONO (-4190 5735);
FORCEPROP 2 LASTPIN (-4200 5675) $PN J5
J 0
(-4190 5685);
DISPLAY 0.680851 (-4190 5685);
PAINT MONO (-4190 5685);
FORCEPROP 2 LASTPIN (-4200 5625) $PN J4
J 0
(-4190 5635);
DISPLAY 0.680851 (-4190 5635);
PAINT MONO (-4190 5635);
FORCEPROP 2 LASTPIN (-4200 5575) $PN J3
J 0
(-4190 5585);
DISPLAY 0.680851 (-4190 5585);
PAINT MONO (-4190 5585);
FORCEPROP 2 LASTPIN (-4200 5525) $PN J2
J 0
(-4190 5535);
DISPLAY 0.680851 (-4190 5535);
PAINT MONO (-4190 5535);
FORCEPROP 2 LASTPIN (-4200 5475) $PN J1
J 0
(-4190 5485);
DISPLAY 0.680851 (-4190 5485);
PAINT MONO (-4190 5485);
FORCEPROP 2 LASTPIN (-4200 5425) $PN K7
J 0
(-4190 5435);
DISPLAY 0.680851 (-4190 5435);
PAINT MONO (-4190 5435);
FORCEPROP 2 LASTPIN (-4200 5375) $PN K6
J 0
(-4190 5385);
DISPLAY 0.680851 (-4190 5385);
PAINT MONO (-4190 5385);
FORCEPROP 2 LASTPIN (-5500 4025) $PN L7
J 2
(-5510 4035);
DISPLAY 0.680851 (-5510 4035);
PAINT MONO (-5510 4035);
FORCEPROP 2 LASTPIN (-5500 3975) $PN K5
J 2
(-5510 3985);
DISPLAY 0.680851 (-5510 3985);
PAINT MONO (-5510 3985);
FORCEPROP 2 LASTPIN (-5500 3925) $PN K4
J 2
(-5510 3935);
DISPLAY 0.680851 (-5510 3935);
PAINT MONO (-5510 3935);
FORCEPROP 2 LASTPIN (-5500 3875) $PN K3
J 2
(-5510 3885);
DISPLAY 0.680851 (-5510 3885);
PAINT MONO (-5510 3885);
FORCEPROP 2 LASTPIN (-5500 3825) $PN K2
J 2
(-5510 3835);
DISPLAY 0.680851 (-5510 3835);
PAINT MONO (-5510 3835);
FORCEPROP 2 LASTPIN (-5500 3775) $PN K1
J 2
(-5510 3785);
DISPLAY 0.680851 (-5510 3785);
PAINT MONO (-5510 3785);
FORCEPROP 2 LASTPIN (-5500 3725) $PN L6
J 2
(-5510 3735);
DISPLAY 0.680851 (-5510 3735);
PAINT MONO (-5510 3735);
FORCEPROP 2 LASTPIN (-5500 3675) $PN L5
J 2
(-5510 3685);
DISPLAY 0.680851 (-5510 3685);
PAINT MONO (-5510 3685);
FORCEPROP 2 LASTPIN (-5500 3625) $PN L1
J 2
(-5510 3635);
DISPLAY 0.680851 (-5510 3635);
PAINT MONO (-5510 3635);
FORCEPROP 2 LASTPIN (-5500 3575) $PN M2
J 2
(-5510 3585);
DISPLAY 0.680851 (-5510 3585);
PAINT MONO (-5510 3585);
FORCEPROP 2 LASTPIN (-5500 3525) $PN L3
J 2
(-5510 3535);
DISPLAY 0.680851 (-5510 3535);
PAINT MONO (-5510 3535);
FORCEPROP 2 LASTPIN (-5500 3475) $PN L4
J 2
(-5510 3485);
DISPLAY 0.680851 (-5510 3485);
PAINT MONO (-5510 3485);
FORCEPROP 2 LASTPIN (-4200 4025) $PN M1
J 0
(-4190 4035);
DISPLAY 0.680851 (-4190 4035);
PAINT MONO (-4190 4035);
FORCEPROP 2 LASTPIN (-4200 3975) $PN N1
J 0
(-4190 3985);
DISPLAY 0.680851 (-4190 3985);
PAINT MONO (-4190 3985);
FORCEPROP 2 LASTPIN (-4200 3925) $PN M6
J 0
(-4190 3935);
DISPLAY 0.680851 (-4190 3935);
PAINT MONO (-4190 3935);
FORCEPROP 2 LASTPIN (-4200 3875) $PN M5
J 0
(-4190 3885);
DISPLAY 0.680851 (-4190 3885);
PAINT MONO (-4190 3885);
FORCEPROP 2 LASTPIN (-4200 3825) $PN N2
J 0
(-4190 3835);
DISPLAY 0.680851 (-4190 3835);
PAINT MONO (-4190 3835);
FORCEPROP 2 LASTPIN (-4200 3775) $PN P1
J 0
(-4190 3785);
DISPLAY 0.680851 (-4190 3785);
PAINT MONO (-4190 3785);
FORCEPROP 2 LASTPIN (-4200 3725) $PN N3
J 0
(-4190 3735);
DISPLAY 0.680851 (-4190 3735);
PAINT MONO (-4190 3735);
FORCEPROP 2 LASTPIN (-4200 3675) $PN N4
J 0
(-4190 3685);
DISPLAY 0.680851 (-4190 3685);
PAINT MONO (-4190 3685);
FORCEPROP 2 LASTPIN (-4200 3625) $PN P2
J 0
(-4190 3635);
DISPLAY 0.680851 (-4190 3635);
PAINT MONO (-4190 3635);
FORCEPROP 2 LASTPIN (-4200 3575) $PN R1
J 0
(-4190 3585);
DISPLAY 0.680851 (-4190 3585);
PAINT MONO (-4190 3585);
FORCEPROP 2 LASTPIN (-4200 3525) $PN P3
J 0
(-4190 3535);
DISPLAY 0.680851 (-4190 3535);
PAINT MONO (-4190 3535);
FORCEPROP 2 LASTPIN (-4200 3475) $PN M7
J 0
(-4190 3485);
DISPLAY 0.680851 (-4190 3485);
PAINT MONO (-4190 3485);
FORCEPROP 2 LASTPIN (-5500 4125) $PN P4
J 2
(-5510 4135);
DISPLAY 0.680851 (-5510 4135);
PAINT MONO (-5510 4135);
FORCEPROP 2 LASTPIN (-5500 4175) $PN N5
J 2
(-5510 4185);
DISPLAY 0.680851 (-5510 4185);
PAINT MONO (-5510 4185);
FORCEPROP 2 LASTPIN (-5500 4225) $PN N6
J 2
(-5510 4235);
DISPLAY 0.680851 (-5510 4235);
PAINT MONO (-5510 4235);
FORCEPROP 2 LASTPIN (-5500 4275) $PN N7
J 2
(-5510 4285);
DISPLAY 0.680851 (-5510 4285);
PAINT MONO (-5510 4285);
FORCEPROP 2 LASTPIN (-5500 4325) $PN R2
J 2
(-5510 4335);
DISPLAY 0.680851 (-5510 4335);
PAINT MONO (-5510 4335);
FORCEPROP 2 LASTPIN (-5500 4375) $PN T1
J 2
(-5510 4385);
DISPLAY 0.680851 (-5510 4385);
PAINT MONO (-5510 4385);
FORCEPROP 2 LASTPIN (-5500 4425) $PN P5
J 2
(-5510 4435);
DISPLAY 0.680851 (-5510 4435);
PAINT MONO (-5510 4435);
FORCEPROP 2 LASTPIN (-5500 4475) $PN P6
J 2
(-5510 4485);
DISPLAY 0.680851 (-5510 4485);
PAINT MONO (-5510 4485);
FORCEPROP 2 LASTPIN (-5500 4525) $PN R3
J 2
(-5510 4535);
DISPLAY 0.680851 (-5510 4535);
PAINT MONO (-5510 4535);
FORCEPROP 2 LASTPIN (-5500 4575) $PN R4
J 2
(-5510 4585);
DISPLAY 0.680851 (-5510 4585);
PAINT MONO (-5510 4585);
FORCEPROP 2 LASTPIN (-5500 4625) $PN R5
J 2
(-5510 4635);
DISPLAY 0.680851 (-5510 4635);
PAINT MONO (-5510 4635);
FORCEPROP 2 LASTPIN (-5500 4675) $PN P7
J 2
(-5510 4685);
DISPLAY 0.680851 (-5510 4685);
PAINT MONO (-5510 4685);
FORCEPROP 2 LASTPIN (-5500 4725) $PN T2
J 2
(-5510 4735);
DISPLAY 0.680851 (-5510 4735);
PAINT MONO (-5510 4735);
FORCEPROP 2 LASTPIN (-5500 4775) $PN U1
J 2
(-5510 4785);
DISPLAY 0.680851 (-5510 4785);
PAINT MONO (-5510 4785);
FORCEPROP 2 LASTPIN (-5500 4825) $PN R6
J 2
(-5510 4835);
DISPLAY 0.680851 (-5510 4835);
PAINT MONO (-5510 4835);
FORCEPROP 2 LASTPIN (-5500 4875) $PN R7
J 2
(-5510 4885);
DISPLAY 0.680851 (-5510 4885);
PAINT MONO (-5510 4885);
FORCEPROP 2 LASTPIN (-5500 4925) $PN T3
J 2
(-5510 4935);
DISPLAY 0.680851 (-5510 4935);
PAINT MONO (-5510 4935);
FORCEPROP 2 LASTPIN (-5500 4975) $PN T4
J 2
(-5510 4985);
DISPLAY 0.680851 (-5510 4985);
PAINT MONO (-5510 4985);
FORCEPROP 2 LASTPIN (-5500 5025) $PN T5
J 2
(-5510 5035);
DISPLAY 0.680851 (-5510 5035);
PAINT MONO (-5510 5035);
FORCEPROP 2 LASTPIN (-5500 5075) $PN T6
J 2
(-5510 5085);
DISPLAY 0.680851 (-5510 5085);
PAINT MONO (-5510 5085);
FORCEPROP 2 LASTPIN (-4200 4325) $PN U2
J 0
(-4190 4335);
DISPLAY 0.680851 (-4190 4335);
PAINT MONO (-4190 4335);
FORCEPROP 2 LASTPIN (-4200 4375) $PN V1
J 0
(-4190 4385);
DISPLAY 0.680851 (-4190 4385);
PAINT MONO (-4190 4385);
FORCEPROP 2 LASTPIN (-4200 4425) $PN U3
J 0
(-4190 4435);
DISPLAY 0.680851 (-4190 4435);
PAINT MONO (-4190 4435);
FORCEPROP 2 LASTPIN (-4200 4475) $PN U4
J 0
(-4190 4485);
DISPLAY 0.680851 (-4190 4485);
PAINT MONO (-4190 4485);
FORCEPROP 2 LASTPIN (-4200 4525) $PN W1
J 0
(-4190 4535);
DISPLAY 0.680851 (-4190 4535);
PAINT MONO (-4190 4535);
FORCEPROP 2 LASTPIN (-4200 4575) $PN W2
J 0
(-4190 4585);
DISPLAY 0.680851 (-4190 4585);
PAINT MONO (-4190 4585);
FORCEPROP 2 LASTPIN (-4200 4625) $PN V4
J 0
(-4190 4635);
DISPLAY 0.680851 (-4190 4635);
PAINT MONO (-4190 4635);
FORCEPROP 2 LASTPIN (-4200 4675) $PN U5
J 0
(-4190 4685);
DISPLAY 0.680851 (-4190 4685);
PAINT MONO (-4190 4685);
FORCEPROP 2 LASTPIN (-4200 4725) $PN Y1
J 0
(-4190 4735);
DISPLAY 0.680851 (-4190 4735);
PAINT MONO (-4190 4735);
FORCEPROP 2 LASTPIN (-4200 4775) $PN AA1
J 0
(-4190 4785);
DISPLAY 0.680851 (-4190 4785);
PAINT MONO (-4190 4785);
FORCEPROP 2 LASTPIN (-4200 4825) $PN W3
J 0
(-4190 4835);
DISPLAY 0.680851 (-4190 4835);
PAINT MONO (-4190 4835);
FORCEPROP 2 LASTPIN (-4200 4875) $PN Y2
J 0
(-4190 4885);
DISPLAY 0.680851 (-4190 4885);
PAINT MONO (-4190 4885);
FORCEPROP 2 LASTPIN (-4200 4925) $PN Y3
J 0
(-4190 4935);
DISPLAY 0.680851 (-4190 4935);
PAINT MONO (-4190 4935);
FORCEPROP 2 LASTPIN (-4200 4975) $PN W4
J 0
(-4190 4985);
DISPLAY 0.680851 (-4190 4985);
PAINT MONO (-4190 4985);
FORCEPROP 2 LASTPIN (-4200 5025) $PN V5
J 0
(-4190 5035);
DISPLAY 0.680851 (-4190 5035);
PAINT MONO (-4190 5035);
FORCEPROP 2 LASTPIN (-4200 5075) $PN T7
J 0
(-4190 5085);
DISPLAY 0.680851 (-4190 5085);
PAINT MONO (-4190 5085);
FORCEPROP 2 LAST PART_TYPE SMLF
J 0
(-5344 6458);
DISPLAY 0.680851 (-5344 6458);
FORCEPROP 2 LAST VALUE LCMXO3LF-9400C-5BG484C
J 0
(-5344 6413);
DISPLAY 0.489362 (-5344 6413);
PAINT SKYBLUE (-5344 6413);
FORCEPROP 1 LAST MATERIAL IC
J 0
(-5351 6188);
DISPLAY 0.723404 (-5351 6188);
PAINT GREEN (-5351 6188);
FORCEPROP 2 LAST CDS_LIB pure_quanta
J 0
(-4850 4775);
DISPLAY INVISIBLE (-4850 4775);
FORCEPROP 1 LAST CDS_LMAN_SYM_OUTLINE -500,1400,500,-1400
J 0
(-4850 4775);
DISPLAY 0.468085 (-4850 4775);
PAINT GREEN (-4850 4775);
DISPLAY INVISIBLE (-4850 4775);
FORCEPROP 1 LAST NEEDS_NO_SIZE TRUE
J 0
(-4850 4775);
DISPLAY 0.723404 (-4850 4775);
PAINT GREEN (-4850 4775);
DISPLAY INVISIBLE (-4850 4775);
FORCEPROP 2 LAST SEC_TYPE 
J 0
(-5325 6500);
DISPLAY 0.680851 (-5325 6500);
DISPLAY INVISIBLE (-5325 6500);
FORCEPROP 1 LAST PATH I143
J 0
(-4850 4775);
DISPLAY 0.723404 (-4850 4775);
PAINT GREEN (-4850 4775);
DISPLAY INVISIBLE (-4850 4775);
FORCEPROP 1 LAST PART_NUMBER AJ094000T08
J 0
(-5351 6315);
DISPLAY 0.723404 (-5351 6315);
PAINT GREEN (-5351 6315);
DISPLAY INVISIBLE (-5351 6315);
FORCEADD OFFPAGE..5
(-7300 5025);
FORCEPROP 2 LAST $XR0 241 
J 0
(-7585 5025);
DISPLAY 0.638298 (-7585 5025);
PAINT MONO (-7585 5025);
FORCEPROP 2 LAST CDS_LIB standard
J 0
(-7300 5025);
DISPLAY INVISIBLE (-7300 5025);
FORCEPROP 1 LAST OFFPAGE TRUE
J 0
(-6975 4900);
DISPLAY 0.872340 (-6975 4900);
PAINT GREEN (-6975 4900);
DISPLAY INVISIBLE (-6975 4900);
FORCEPROP 1 LAST COMMENT_BODY TRUE
J 0
(-7200 4950);
DISPLAY 0.872340 (-7200 4950);
PAINT GREEN (-7200 4950);
DISPLAY INVISIBLE (-7200 4950);
FORCEPROP 2 LAST PATH I145
J 0
(-7575 5075);
DISPLAY 0.680851 (-7575 5075);
DISPLAY INVISIBLE (-7575 5075);
FORCEADD Q_RES..1
(-6450 5025);
FORCEPROP 1 LAST LOCATION R6073
J 0
(-6325 5025);
DISPLAY 0.489362 (-6325 5025);
PAINT SKYBLUE (-6325 5025);
FORCEPROP 0 LAST $SEC 1
J 0
(-6325 5075);
DISPLAY 0.680851 (-6325 5075);
PAINT MONO (-6325 5075);
DISPLAY INVISIBLE (-6325 5075);
FORCEPROP 0 LAST CDS_SEC 1
J 0
(-6325 5075);
DISPLAY 1.021277 (-6325 5075);
DISPLAY INVISIBLE (-6325 5075);
FORCEPROP 1 LASTPIN (-6550 5025) $PN 1
J 0
(-6538 5037);
DISPLAY 0.489362 (-6538 5037);
PAINT MONO (-6538 5037);
FORCEPROP 1 LASTPIN (-6350 5025) $PN 2
J 0
(-6388 5037);
DISPLAY 0.489362 (-6388 5037);
PAINT MONO (-6388 5037);
FORCEPROP 1 LAST VALUE 0
J 2
(-6575 5025);
DISPLAY 0.489362 (-6575 5025);
PAINT SKYBLUE (-6575 5025);
FORCEPROP 1 LAST PACK_TYPE 0402LF
J 2
(-6275 4950);
DISPLAY 0.489362 (-6275 4950);
PAINT SKYBLUE (-6275 4950);
DISPLAY INVISIBLE (-6275 4950);
FORCEPROP 1 LAST TOLERANCE 5%
J 0
(-6575 5000);
DISPLAY 0.489362 (-6575 5000);
PAINT SKYBLUE (-6575 5000);
DISPLAY INVISIBLE (-6575 5000);
FORCEPROP 1 LAST MATERIAL CHIP
J 2
(-6275 5000);
DISPLAY 0.489362 (-6275 5000);
PAINT SKYBLUE (-6275 5000);
DISPLAY INVISIBLE (-6275 5000);
FORCEPROP 1 LAST WATTAGE 1/16W
J 2
(-6525 4950);
DISPLAY 0.489362 (-6525 4950);
PAINT SKYBLUE (-6525 4950);
DISPLAY INVISIBLE (-6525 4950);
FORCEPROP 2 LAST BOM_COST MEM
J 2
(-6425 5175);
DISPLAY 0.744681 (-6425 5175);
PAINT WHITE (-6425 5175);
DISPLAY INVISIBLE (-6425 5175);
FORCEPROP 2 LAST CDS_LIB pure_quanta
J 2
(-6450 5025);
DISPLAY INVISIBLE (-6450 5025);
FORCEPROP 1 LAST PATH I146
J 0
(-6500 5175);
DISPLAY 0.978723 (-6500 5175);
PAINT WHITE (-6500 5175);
DISPLAY INVISIBLE (-6500 5175);
FORCEPROP 1 LAST PART_NUMBER CS00002JB13
J 2
(-6350 5075);
DISPLAY 0.489362 (-6350 5075);
PAINT SKYBLUE (-6350 5075);
DISPLAY INVISIBLE (-6350 5075);
FORCEADD OFFPAGE..5
(-7300 3475);
FORCEPROP 2 LAST $XR0 249 
J 0
(-7585 3475);
DISPLAY 0.638298 (-7585 3475);
PAINT MONO (-7585 3475);
FORCEPROP 2 LAST CDS_LIB standard
J 0
(-7300 3475);
DISPLAY INVISIBLE (-7300 3475);
FORCEPROP 1 LAST OFFPAGE TRUE
J 0
(-6975 3350);
DISPLAY 0.872340 (-6975 3350);
PAINT GREEN (-6975 3350);
DISPLAY INVISIBLE (-6975 3350);
FORCEPROP 1 LAST COMMENT_BODY TRUE
J 0
(-7200 3400);
DISPLAY 0.872340 (-7200 3400);
PAINT GREEN (-7200 3400);
DISPLAY INVISIBLE (-7200 3400);
FORCEPROP 2 LAST PATH I147
J 0
(-7575 3525);
DISPLAY 0.680851 (-7575 3525);
DISPLAY INVISIBLE (-7575 3525);
FORCEADD OFFPAGE..1
(-7300 3525);
FORCEPROP 2 LAST $XR0 85 
J 0
(-7521 3525);
DISPLAY 0.638298 (-7521 3525);
PAINT MONO (-7521 3525);
FORCEPROP 2 LAST CDS_LIB standard
J 0
(-7300 3525);
DISPLAY INVISIBLE (-7300 3525);
FORCEPROP 1 LAST OFFPAGE TRUE
J 0
(-6975 3400);
DISPLAY 0.872340 (-6975 3400);
PAINT GREEN (-6975 3400);
DISPLAY INVISIBLE (-6975 3400);
FORCEPROP 1 LAST COMMENT_BODY TRUE
J 0
(-7175 3425);
DISPLAY 0.872340 (-7175 3425);
PAINT GREEN (-7175 3425);
DISPLAY INVISIBLE (-7175 3425);
FORCEPROP 2 LAST PATH I148
J 0
(-7550 3575);
DISPLAY 0.680851 (-7550 3575);
DISPLAY INVISIBLE (-7550 3575);
FORCEADD OFFPAGE..1
(-7300 3625);
FORCEPROP 2 LAST $XR0 85 
J 0
(-7521 3625);
DISPLAY 0.638298 (-7521 3625);
PAINT MONO (-7521 3625);
FORCEPROP 2 LAST CDS_LIB standard
J 0
(-7300 3625);
DISPLAY INVISIBLE (-7300 3625);
FORCEPROP 1 LAST OFFPAGE TRUE
J 0
(-6975 3500);
DISPLAY 0.872340 (-6975 3500);
PAINT GREEN (-6975 3500);
DISPLAY INVISIBLE (-6975 3500);
FORCEPROP 1 LAST COMMENT_BODY TRUE
J 0
(-7175 3525);
DISPLAY 0.872340 (-7175 3525);
PAINT GREEN (-7175 3525);
DISPLAY INVISIBLE (-7175 3525);
FORCEPROP 2 LAST PATH I149
J 0
(-7550 3675);
DISPLAY 0.680851 (-7550 3675);
DISPLAY INVISIBLE (-7550 3675);
FORCEADD OFFPAGE..1
(-7300 4375);
FORCEPROP 2 LAST $XR0 54 
J 0
(-7551 4375);
DISPLAY 0.638298 (-7551 4375);
PAINT MONO (-7551 4375);
FORCEPROP 2 LAST CDS_LIB standard
J 0
(-7300 4375);
DISPLAY INVISIBLE (-7300 4375);
FORCEPROP 1 LAST OFFPAGE TRUE
J 0
(-6975 4250);
DISPLAY 0.872340 (-6975 4250);
PAINT GREEN (-6975 4250);
DISPLAY INVISIBLE (-6975 4250);
FORCEPROP 1 LAST COMMENT_BODY TRUE
J 0
(-7175 4275);
DISPLAY 0.872340 (-7175 4275);
PAINT GREEN (-7175 4275);
DISPLAY INVISIBLE (-7175 4275);
FORCEPROP 2 LAST PATH I15
J 0
(-7500 4425);
DISPLAY 0.680851 (-7500 4425);
DISPLAY INVISIBLE (-7500 4425);
FORCEADD OFFPAGE..1
R 2
(-2325 4025);
FORCEPROP 2 LAST $XR0 238 
J 0
(-2139 4025);
DISPLAY 0.638298 (-2139 4025);
PAINT MONO (-2139 4025);
FORCEPROP 2 LAST CDS_LIB standard
J 0
(-2325 4025);
DISPLAY INVISIBLE (-2325 4025);
FORCEPROP 1 LAST OFFPAGE TRUE
J 2
(-2650 3900);
DISPLAY 0.872340 (-2650 3900);
PAINT GREEN (-2650 3900);
DISPLAY INVISIBLE (-2650 3900);
FORCEPROP 1 LAST COMMENT_BODY TRUE
J 2
(-2450 3925);
DISPLAY 0.872340 (-2450 3925);
PAINT GREEN (-2450 3925);
DISPLAY INVISIBLE (-2450 3925);
FORCEPROP 2 LAST PATH I150
J 0
(-2025 4075);
DISPLAY 0.680851 (-2025 4075);
DISPLAY INVISIBLE (-2025 4075);
FORCEADD OFFPAGE..1
(-7300 3975);
FORCEPROP 2 LAST $XR0 238 
J 0
(-7552 3975);
DISPLAY 0.638298 (-7552 3975);
PAINT MONO (-7552 3975);
FORCEPROP 2 LAST CDS_LIB standard
J 0
(-7300 3975);
DISPLAY INVISIBLE (-7300 3975);
FORCEPROP 1 LAST OFFPAGE TRUE
J 0
(-6975 3850);
DISPLAY 0.872340 (-6975 3850);
PAINT GREEN (-6975 3850);
DISPLAY INVISIBLE (-6975 3850);
FORCEPROP 1 LAST COMMENT_BODY TRUE
J 0
(-7175 3875);
DISPLAY 0.872340 (-7175 3875);
PAINT GREEN (-7175 3875);
DISPLAY INVISIBLE (-7175 3875);
FORCEPROP 2 LAST PATH I153
J 0
(-7550 4025);
DISPLAY 0.680851 (-7550 4025);
DISPLAY INVISIBLE (-7550 4025);
FORCEADD OFFPAGE..1
R 2
(-2325 4475);
FORCEPROP 2 LAST $XR0 85 
J 0
(-2139 4475);
DISPLAY 0.638298 (-2139 4475);
PAINT MONO (-2139 4475);
FORCEPROP 2 LAST CDS_LIB standard
J 0
(-2325 4475);
DISPLAY INVISIBLE (-2325 4475);
FORCEPROP 1 LAST OFFPAGE TRUE
J 2
(-2650 4350);
DISPLAY 0.872340 (-2650 4350);
PAINT GREEN (-2650 4350);
DISPLAY INVISIBLE (-2650 4350);
FORCEPROP 1 LAST COMMENT_BODY TRUE
J 2
(-2450 4375);
DISPLAY 0.872340 (-2450 4375);
PAINT GREEN (-2450 4375);
DISPLAY INVISIBLE (-2450 4375);
FORCEPROP 2 LAST PATH I154
J 0
(-2150 4550);
DISPLAY 0.680851 (-2150 4550);
DISPLAY INVISIBLE (-2150 4550);
FORCEADD OFFPAGE..2
(-2325 4675);
FORCEPROP 2 LAST $XR0 256 
J 0
(-2136 4675);
DISPLAY 0.638298 (-2136 4675);
PAINT MONO (-2136 4675);
FORCEPROP 2 LAST CDS_LIB standard
J 0
(-2325 4675);
DISPLAY INVISIBLE (-2325 4675);
FORCEPROP 1 LAST OFFPAGE TRUE
J 0
(-2000 4550);
DISPLAY 0.872340 (-2000 4550);
PAINT GREEN (-2000 4550);
DISPLAY INVISIBLE (-2000 4550);
FORCEPROP 1 LAST COMMENT_BODY TRUE
J 0
(-2370 4580);
DISPLAY 0.872340 (-2370 4580);
PAINT GREEN (-2370 4580);
DISPLAY INVISIBLE (-2370 4580);
FORCEPROP 2 LAST PATH I155
J 0
(-2125 4725);
DISPLAY 0.680851 (-2125 4725);
DISPLAY INVISIBLE (-2125 4725);
FORCEADD OFFPAGE..2
(-2325 4625);
FORCEPROP 2 LAST $XR0 256 
J 0
(-2136 4625);
DISPLAY 0.638298 (-2136 4625);
PAINT MONO (-2136 4625);
FORCEPROP 2 LAST CDS_LIB standard
J 0
(-2325 4625);
DISPLAY INVISIBLE (-2325 4625);
FORCEPROP 1 LAST OFFPAGE TRUE
J 0
(-2000 4500);
DISPLAY 0.872340 (-2000 4500);
PAINT GREEN (-2000 4500);
DISPLAY INVISIBLE (-2000 4500);
FORCEPROP 1 LAST COMMENT_BODY TRUE
J 0
(-2370 4530);
DISPLAY 0.872340 (-2370 4530);
PAINT GREEN (-2370 4530);
DISPLAY INVISIBLE (-2370 4530);
FORCEPROP 2 LAST PATH I156
J 0
(-2150 4700);
DISPLAY 0.680851 (-2150 4700);
DISPLAY INVISIBLE (-2150 4700);
FORCEADD OFFPAGE..5
(-7300 4625);
FORCEPROP 2 LAST $XR0 256 
J 0
(-7585 4625);
DISPLAY 0.638298 (-7585 4625);
PAINT MONO (-7585 4625);
FORCEPROP 2 LAST CDS_LIB standard
J 0
(-7300 4625);
DISPLAY INVISIBLE (-7300 4625);
FORCEPROP 1 LAST OFFPAGE TRUE
J 0
(-6975 4500);
DISPLAY 0.872340 (-6975 4500);
PAINT GREEN (-6975 4500);
DISPLAY INVISIBLE (-6975 4500);
FORCEPROP 1 LAST COMMENT_BODY TRUE
J 0
(-7200 4550);
DISPLAY 0.872340 (-7200 4550);
PAINT GREEN (-7200 4550);
DISPLAY INVISIBLE (-7200 4550);
FORCEPROP 2 LAST PATH I157
J 0
(-7250 4700);
DISPLAY 0.680851 (-7250 4700);
DISPLAY INVISIBLE (-7250 4700);
FORCEADD OFFPAGE..1
R 2
(-2125 5475);
FORCEPROP 2 LAST $XR0 84 
J 0
(-1939 5475);
DISPLAY 0.638298 (-1939 5475);
PAINT MONO (-1939 5475);
FORCEPROP 2 LAST CDS_LIB standard
J 0
(-2125 5475);
DISPLAY INVISIBLE (-2125 5475);
FORCEPROP 1 LAST OFFPAGE TRUE
J 2
(-2450 5350);
DISPLAY 0.872340 (-2450 5350);
PAINT GREEN (-2450 5350);
DISPLAY INVISIBLE (-2450 5350);
FORCEPROP 1 LAST COMMENT_BODY TRUE
J 2
(-2250 5375);
DISPLAY 0.872340 (-2250 5375);
PAINT GREEN (-2250 5375);
DISPLAY INVISIBLE (-2250 5375);
FORCEPROP 2 LAST PATH I158
J 0
(-1950 5550);
DISPLAY 0.680851 (-1950 5550);
DISPLAY INVISIBLE (-1950 5550);
FORCEADD OFFPAGE..1
R 2
(-2125 5425);
FORCEPROP 2 LAST $XR0 84 
J 0
(-1939 5425);
DISPLAY 0.638298 (-1939 5425);
PAINT MONO (-1939 5425);
FORCEPROP 2 LAST CDS_LIB standard
J 0
(-2125 5425);
DISPLAY INVISIBLE (-2125 5425);
FORCEPROP 1 LAST OFFPAGE TRUE
J 2
(-2450 5300);
DISPLAY 0.872340 (-2450 5300);
PAINT GREEN (-2450 5300);
DISPLAY INVISIBLE (-2450 5300);
FORCEPROP 1 LAST COMMENT_BODY TRUE
J 2
(-2250 5325);
DISPLAY 0.872340 (-2250 5325);
PAINT GREEN (-2250 5325);
DISPLAY INVISIBLE (-2250 5325);
FORCEPROP 2 LAST PATH I159
J 0
(-1950 5500);
DISPLAY 0.680851 (-1950 5500);
DISPLAY INVISIBLE (-1950 5500);
FORCEADD OFFPAGE..1
(-7300 4575);
FORCEPROP 2 LAST $XR0 54 
J 0
(-7551 4575);
DISPLAY 0.638298 (-7551 4575);
PAINT MONO (-7551 4575);
FORCEPROP 2 LAST CDS_LIB standard
J 0
(-7300 4575);
DISPLAY INVISIBLE (-7300 4575);
FORCEPROP 1 LAST OFFPAGE TRUE
J 0
(-6975 4450);
DISPLAY 0.872340 (-6975 4450);
PAINT GREEN (-6975 4450);
DISPLAY INVISIBLE (-6975 4450);
FORCEPROP 1 LAST COMMENT_BODY TRUE
J 0
(-7175 4475);
DISPLAY 0.872340 (-7175 4475);
PAINT GREEN (-7175 4475);
DISPLAY INVISIBLE (-7175 4475);
FORCEPROP 2 LAST PATH I16
J 0
(-7550 4625);
DISPLAY 0.680851 (-7550 4625);
DISPLAY INVISIBLE (-7550 4625);
FORCEADD OFFPAGE..1
R 2
(-2125 5375);
FORCEPROP 2 LAST $XR0 84 
J 0
(-1939 5375);
DISPLAY 0.638298 (-1939 5375);
PAINT MONO (-1939 5375);
FORCEPROP 2 LAST CDS_LIB standard
J 0
(-2125 5375);
DISPLAY INVISIBLE (-2125 5375);
FORCEPROP 1 LAST OFFPAGE TRUE
J 2
(-2450 5250);
DISPLAY 0.872340 (-2450 5250);
PAINT GREEN (-2450 5250);
DISPLAY INVISIBLE (-2450 5250);
FORCEPROP 1 LAST COMMENT_BODY TRUE
J 2
(-2250 5275);
DISPLAY 0.872340 (-2250 5275);
PAINT GREEN (-2250 5275);
DISPLAY INVISIBLE (-2250 5275);
FORCEPROP 2 LAST PATH I160
J 0
(-1950 5450);
DISPLAY 0.680851 (-1950 5450);
DISPLAY INVISIBLE (-1950 5450);
FORCEADD Q_RES..1
(-6325 3825);
FORCEPROP 1 LAST LOCATION R6183
J 0
(-6200 3825);
DISPLAY 0.489362 (-6200 3825);
PAINT SKYBLUE (-6200 3825);
FORCEPROP 0 LAST $SEC 1
J 0
(-6200 3850);
DISPLAY 0.680851 (-6200 3850);
PAINT MONO (-6200 3850);
DISPLAY INVISIBLE (-6200 3850);
FORCEPROP 0 LAST CDS_SEC 1
J 0
(-6200 3850);
DISPLAY 0.680851 (-6200 3850);
DISPLAY INVISIBLE (-6200 3850);
FORCEPROP 1 LASTPIN (-6425 3825) $PN 1
J 0
(-6413 3837);
DISPLAY 0.787234 (-6413 3837);
PAINT MONO (-6413 3837);
FORCEPROP 1 LASTPIN (-6225 3825) $PN 2
J 0
(-6263 3837);
DISPLAY 0.787234 (-6263 3837);
PAINT MONO (-6263 3837);
FORCEPROP 1 LAST VALUE 0
J 2
(-6450 3825);
DISPLAY 0.489362 (-6450 3825);
PAINT SKYBLUE (-6450 3825);
FORCEPROP 2 LAST BOM_COST MEM
J 2
(-6300 3975);
DISPLAY 0.744681 (-6300 3975);
PAINT WHITE (-6300 3975);
DISPLAY INVISIBLE (-6300 3975);
FORCEPROP 1 LAST WATTAGE 1/16W
J 2
(-6400 3750);
DISPLAY 0.489362 (-6400 3750);
PAINT SKYBLUE (-6400 3750);
DISPLAY INVISIBLE (-6400 3750);
FORCEPROP 1 LAST MATERIAL CHIP
J 2
(-6150 3800);
DISPLAY 0.489362 (-6150 3800);
PAINT SKYBLUE (-6150 3800);
DISPLAY INVISIBLE (-6150 3800);
FORCEPROP 1 LAST TOLERANCE 5%
J 0
(-6450 3800);
DISPLAY 0.489362 (-6450 3800);
PAINT SKYBLUE (-6450 3800);
DISPLAY INVISIBLE (-6450 3800);
FORCEPROP 1 LAST PACK_TYPE 0402LF
J 2
(-6150 3750);
DISPLAY 0.489362 (-6150 3750);
PAINT SKYBLUE (-6150 3750);
DISPLAY INVISIBLE (-6150 3750);
FORCEPROP 2 LAST CDS_LIB pure_quanta
J 0
(-6325 3825);
DISPLAY INVISIBLE (-6325 3825);
FORCEPROP 1 LAST PATH I164
J 0
(-6375 3975);
DISPLAY 0.978723 (-6375 3975);
PAINT WHITE (-6375 3975);
DISPLAY INVISIBLE (-6375 3975);
FORCEPROP 1 LAST PART_NUMBER CS00002JB13
J 2
(-6225 3875);
DISPLAY 0.489362 (-6225 3875);
PAINT SKYBLUE (-6225 3875);
DISPLAY INVISIBLE (-6225 3875);
FORCEADD Q_RES..1
(-6325 3775);
FORCEPROP 1 LAST LOCATION R6184
J 0
(-6200 3775);
DISPLAY 0.489362 (-6200 3775);
PAINT SKYBLUE (-6200 3775);
FORCEPROP 0 LAST $SEC 1
J 0
(-6200 3800);
DISPLAY 0.680851 (-6200 3800);
PAINT MONO (-6200 3800);
DISPLAY INVISIBLE (-6200 3800);
FORCEPROP 0 LAST CDS_SEC 1
J 0
(-6200 3800);
DISPLAY 0.680851 (-6200 3800);
DISPLAY INVISIBLE (-6200 3800);
FORCEPROP 1 LASTPIN (-6425 3775) $PN 1
J 0
(-6413 3787);
DISPLAY 0.787234 (-6413 3787);
PAINT MONO (-6413 3787);
FORCEPROP 1 LASTPIN (-6225 3775) $PN 2
J 0
(-6263 3787);
DISPLAY 0.787234 (-6263 3787);
PAINT MONO (-6263 3787);
FORCEPROP 1 LAST VALUE 0
J 2
(-6450 3775);
DISPLAY 0.489362 (-6450 3775);
PAINT SKYBLUE (-6450 3775);
FORCEPROP 2 LAST CDS_LIB pure_quanta
J 0
(-6325 3775);
DISPLAY INVISIBLE (-6325 3775);
FORCEPROP 1 LAST PACK_TYPE 0402LF
J 2
(-6150 3700);
DISPLAY 0.489362 (-6150 3700);
PAINT SKYBLUE (-6150 3700);
DISPLAY INVISIBLE (-6150 3700);
FORCEPROP 1 LAST TOLERANCE 5%
J 0
(-6450 3750);
DISPLAY 0.489362 (-6450 3750);
PAINT SKYBLUE (-6450 3750);
DISPLAY INVISIBLE (-6450 3750);
FORCEPROP 1 LAST MATERIAL CHIP
J 2
(-6150 3750);
DISPLAY 0.489362 (-6150 3750);
PAINT SKYBLUE (-6150 3750);
DISPLAY INVISIBLE (-6150 3750);
FORCEPROP 1 LAST WATTAGE 1/16W
J 2
(-6400 3700);
DISPLAY 0.489362 (-6400 3700);
PAINT SKYBLUE (-6400 3700);
DISPLAY INVISIBLE (-6400 3700);
FORCEPROP 2 LAST BOM_COST MEM
J 2
(-6300 3925);
DISPLAY 0.744681 (-6300 3925);
PAINT WHITE (-6300 3925);
DISPLAY INVISIBLE (-6300 3925);
FORCEPROP 1 LAST PATH I165
J 0
(-6375 3925);
DISPLAY 0.978723 (-6375 3925);
PAINT WHITE (-6375 3925);
DISPLAY INVISIBLE (-6375 3925);
FORCEPROP 1 LAST PART_NUMBER CS00002JB13
J 2
(-6225 3825);
DISPLAY 0.489362 (-6225 3825);
PAINT SKYBLUE (-6225 3825);
DISPLAY INVISIBLE (-6225 3825);
FORCEADD OFFPAGE..5
(-7325 3825);
FORCEPROP 2 LAST $XR1 161 
J 0
(-7669 3825);
DISPLAY 0.638298 (-7669 3825);
PAINT MONO (-7669 3825);
FORCEPROP 2 LAST $XR0 83 
J 0
(-7549 3825);
DISPLAY 0.638298 (-7549 3825);
PAINT MONO (-7549 3825);
FORCEPROP 2 LAST CDS_LIB standard
J 0
(-7325 3825);
DISPLAY INVISIBLE (-7325 3825);
FORCEPROP 1 LAST OFFPAGE TRUE
J 0
(-7000 3700);
DISPLAY 0.872340 (-7000 3700);
PAINT GREEN (-7000 3700);
DISPLAY INVISIBLE (-7000 3700);
FORCEPROP 1 LAST COMMENT_BODY TRUE
J 0
(-7225 3750);
DISPLAY 0.872340 (-7225 3750);
PAINT GREEN (-7225 3750);
DISPLAY INVISIBLE (-7225 3750);
FORCEPROP 2 LAST PATH I166
J 0
(-7275 3900);
DISPLAY 0.680851 (-7275 3900);
DISPLAY INVISIBLE (-7275 3900);
FORCEADD OFFPAGE..5
(-7325 3775);
FORCEPROP 2 LAST $XR1 161 
J 0
(-7669 3775);
DISPLAY 0.638298 (-7669 3775);
PAINT MONO (-7669 3775);
FORCEPROP 2 LAST $XR0 83 
J 0
(-7549 3775);
DISPLAY 0.638298 (-7549 3775);
PAINT MONO (-7549 3775);
FORCEPROP 2 LAST CDS_LIB standard
J 0
(-7325 3775);
DISPLAY INVISIBLE (-7325 3775);
FORCEPROP 1 LAST OFFPAGE TRUE
J 0
(-7000 3650);
DISPLAY 0.872340 (-7000 3650);
PAINT GREEN (-7000 3650);
DISPLAY INVISIBLE (-7000 3650);
FORCEPROP 1 LAST COMMENT_BODY TRUE
J 0
(-7225 3700);
DISPLAY 0.872340 (-7225 3700);
PAINT GREEN (-7225 3700);
DISPLAY INVISIBLE (-7225 3700);
FORCEPROP 2 LAST PATH I167
J 0
(-7275 3850);
DISPLAY 0.680851 (-7275 3850);
DISPLAY INVISIBLE (-7275 3850);
FORCEADD Q_RES..1
(-6450 4475);
FORCEPROP 1 LAST LOCATION R132
J 0
(-6325 4475);
DISPLAY 0.489362 (-6325 4475);
PAINT SKYBLUE (-6325 4475);
FORCEPROP 0 LAST $SEC 1
J 0
(-6325 4500);
DISPLAY 0.680851 (-6325 4500);
PAINT MONO (-6325 4500);
DISPLAY INVISIBLE (-6325 4500);
FORCEPROP 0 LAST CDS_SEC 1
J 0
(-6325 4500);
DISPLAY 0.680851 (-6325 4500);
DISPLAY INVISIBLE (-6325 4500);
FORCEPROP 1 LASTPIN (-6550 4475) $PN 1
J 0
(-6538 4487);
DISPLAY 0.787234 (-6538 4487);
PAINT MONO (-6538 4487);
FORCEPROP 1 LASTPIN (-6350 4475) $PN 2
J 0
(-6388 4487);
DISPLAY 0.787234 (-6388 4487);
PAINT MONO (-6388 4487);
FORCEPROP 1 LAST VALUE 0
J 2
(-6575 4475);
DISPLAY 0.489362 (-6575 4475);
PAINT SKYBLUE (-6575 4475);
FORCEPROP 2 LAST CDS_LIB pure_quanta
J 0
(-6450 4475);
DISPLAY INVISIBLE (-6450 4475);
FORCEPROP 1 LAST PACK_TYPE 0402LF
J 2
(-6275 4400);
DISPLAY 0.489362 (-6275 4400);
PAINT SKYBLUE (-6275 4400);
DISPLAY INVISIBLE (-6275 4400);
FORCEPROP 1 LAST TOLERANCE 5%
J 0
(-6575 4450);
DISPLAY 0.489362 (-6575 4450);
PAINT SKYBLUE (-6575 4450);
DISPLAY INVISIBLE (-6575 4450);
FORCEPROP 1 LAST MATERIAL CHIP
J 2
(-6275 4450);
DISPLAY 0.489362 (-6275 4450);
PAINT SKYBLUE (-6275 4450);
DISPLAY INVISIBLE (-6275 4450);
FORCEPROP 1 LAST WATTAGE 1/16W
J 2
(-6525 4400);
DISPLAY 0.489362 (-6525 4400);
PAINT SKYBLUE (-6525 4400);
DISPLAY INVISIBLE (-6525 4400);
FORCEPROP 2 LAST BOM_COST MEM
J 2
(-6425 4625);
DISPLAY 0.744681 (-6425 4625);
PAINT WHITE (-6425 4625);
DISPLAY INVISIBLE (-6425 4625);
FORCEPROP 1 LAST PATH I168
J 0
(-6500 4625);
DISPLAY 0.978723 (-6500 4625);
PAINT WHITE (-6500 4625);
DISPLAY INVISIBLE (-6500 4625);
FORCEPROP 1 LAST PART_NUMBER CS00002JB13
J 2
(-6350 4525);
DISPLAY 0.489362 (-6350 4525);
PAINT SKYBLUE (-6350 4525);
DISPLAY INVISIBLE (-6350 4525);
FORCEADD Q_RES..1
(-6450 4425);
FORCEPROP 1 LAST LOCATION R133
J 0
(-6325 4425);
DISPLAY 0.638298 (-6325 4425);
FORCEPROP 0 LAST $SEC 1
J 0
(-6325 4475);
DISPLAY 0.680851 (-6325 4475);
PAINT MONO (-6325 4475);
DISPLAY INVISIBLE (-6325 4475);
FORCEPROP 0 LAST CDS_SEC 1
J 0
(-6325 4475);
DISPLAY 0.680851 (-6325 4475);
DISPLAY INVISIBLE (-6325 4475);
FORCEPROP 1 LASTPIN (-6550 4425) $PN 1
J 0
(-6538 4437);
DISPLAY 0.787234 (-6538 4437);
PAINT MONO (-6538 4437);
FORCEPROP 1 LASTPIN (-6350 4425) $PN 2
J 0
(-6388 4437);
DISPLAY 0.787234 (-6388 4437);
PAINT MONO (-6388 4437);
FORCEPROP 1 LAST VALUE 0
J 2
(-6575 4425);
DISPLAY 0.489362 (-6575 4425);
PAINT SKYBLUE (-6575 4425);
FORCEPROP 1 LAST PACK_TYPE 0402LF
J 2
(-6275 4350);
DISPLAY 0.489362 (-6275 4350);
PAINT SKYBLUE (-6275 4350);
DISPLAY INVISIBLE (-6275 4350);
FORCEPROP 1 LAST TOLERANCE 5%
J 0
(-6575 4400);
DISPLAY 0.489362 (-6575 4400);
PAINT SKYBLUE (-6575 4400);
DISPLAY INVISIBLE (-6575 4400);
FORCEPROP 1 LAST MATERIAL CHIP
J 2
(-6275 4400);
DISPLAY 0.489362 (-6275 4400);
PAINT SKYBLUE (-6275 4400);
DISPLAY INVISIBLE (-6275 4400);
FORCEPROP 1 LAST WATTAGE 1/16W
J 2
(-6525 4350);
DISPLAY 0.489362 (-6525 4350);
PAINT SKYBLUE (-6525 4350);
DISPLAY INVISIBLE (-6525 4350);
FORCEPROP 2 LAST BOM_COST MEM
J 2
(-6425 4575);
DISPLAY 0.744681 (-6425 4575);
PAINT WHITE (-6425 4575);
DISPLAY INVISIBLE (-6425 4575);
FORCEPROP 2 LAST CDS_LIB pure_quanta
J 0
(-6450 4425);
DISPLAY INVISIBLE (-6450 4425);
FORCEPROP 1 LAST PATH I169
J 0
(-6500 4575);
DISPLAY 0.978723 (-6500 4575);
PAINT WHITE (-6500 4575);
DISPLAY INVISIBLE (-6500 4575);
FORCEPROP 1 LAST PART_NUMBER CS00002JB13
J 2
(-6350 4475);
DISPLAY 0.489362 (-6350 4475);
PAINT SKYBLUE (-6350 4475);
DISPLAY INVISIBLE (-6350 4475);
FORCEADD OFFPAGE..1
(-7300 4775);
FORCEPROP 2 LAST $XR0 27 
J 0
(-7521 4775);
DISPLAY 0.638298 (-7521 4775);
PAINT MONO (-7521 4775);
FORCEPROP 2 LAST CDS_LIB standard
J 0
(-7300 4775);
DISPLAY INVISIBLE (-7300 4775);
FORCEPROP 1 LAST OFFPAGE TRUE
J 0
(-6975 4650);
DISPLAY 0.872340 (-6975 4650);
PAINT GREEN (-6975 4650);
DISPLAY INVISIBLE (-6975 4650);
FORCEPROP 1 LAST COMMENT_BODY TRUE
J 0
(-7175 4675);
DISPLAY 0.872340 (-7175 4675);
PAINT GREEN (-7175 4675);
DISPLAY INVISIBLE (-7175 4675);
FORCEPROP 2 LAST PATH I17
J 0
(-7500 4825);
DISPLAY 0.680851 (-7500 4825);
DISPLAY INVISIBLE (-7500 4825);
FORCEADD OFFPAGE..5
(-7325 4475);
FORCEPROP 2 LAST $XR1 161 
J 0
(-7669 4475);
DISPLAY 0.638298 (-7669 4475);
PAINT MONO (-7669 4475);
FORCEPROP 2 LAST $XR0 83 
J 0
(-7549 4475);
DISPLAY 0.638298 (-7549 4475);
PAINT MONO (-7549 4475);
FORCEPROP 2 LAST CDS_LIB standard
J 0
(-7325 4475);
DISPLAY INVISIBLE (-7325 4475);
FORCEPROP 1 LAST OFFPAGE TRUE
J 0
(-7000 4350);
DISPLAY 0.872340 (-7000 4350);
PAINT GREEN (-7000 4350);
DISPLAY INVISIBLE (-7000 4350);
FORCEPROP 1 LAST COMMENT_BODY TRUE
J 0
(-7225 4400);
DISPLAY 0.872340 (-7225 4400);
PAINT GREEN (-7225 4400);
DISPLAY INVISIBLE (-7225 4400);
FORCEPROP 2 LAST PATH I170
J 0
(-7275 4550);
DISPLAY 0.680851 (-7275 4550);
DISPLAY INVISIBLE (-7275 4550);
FORCEADD OFFPAGE..5
(-7325 4425);
FORCEPROP 2 LAST $XR1 161 
J 0
(-7669 4425);
DISPLAY 0.638298 (-7669 4425);
PAINT MONO (-7669 4425);
FORCEPROP 2 LAST $XR0 83 
J 0
(-7549 4425);
DISPLAY 0.638298 (-7549 4425);
PAINT MONO (-7549 4425);
FORCEPROP 2 LAST CDS_LIB standard
J 0
(-7325 4425);
DISPLAY INVISIBLE (-7325 4425);
FORCEPROP 1 LAST OFFPAGE TRUE
J 0
(-7000 4300);
DISPLAY 0.872340 (-7000 4300);
PAINT GREEN (-7000 4300);
DISPLAY INVISIBLE (-7000 4300);
FORCEPROP 1 LAST COMMENT_BODY TRUE
J 0
(-7225 4350);
DISPLAY 0.872340 (-7225 4350);
PAINT GREEN (-7225 4350);
DISPLAY INVISIBLE (-7225 4350);
FORCEPROP 2 LAST PATH I171
J 0
(-7275 4500);
DISPLAY 0.680851 (-7275 4500);
DISPLAY INVISIBLE (-7275 4500);
FORCEADD OFFPAGE..1
(-7300 4275);
FORCEPROP 2 LAST $XR0 268 
J 0
(-7552 4275);
DISPLAY 0.638298 (-7552 4275);
PAINT MONO (-7552 4275);
FORCEPROP 2 LAST CDS_LIB standard
J 0
(-7300 4275);
DISPLAY INVISIBLE (-7300 4275);
FORCEPROP 1 LAST OFFPAGE TRUE
J 0
(-6975 4150);
DISPLAY 0.872340 (-6975 4150);
PAINT GREEN (-6975 4150);
DISPLAY INVISIBLE (-6975 4150);
FORCEPROP 1 LAST COMMENT_BODY TRUE
J 0
(-7175 4175);
DISPLAY 0.872340 (-7175 4175);
PAINT GREEN (-7175 4175);
DISPLAY INVISIBLE (-7175 4175);
FORCEPROP 2 LAST PATH I172
J 0
(-7250 4350);
DISPLAY 0.680851 (-7250 4350);
DISPLAY INVISIBLE (-7250 4350);
FORCEADD OFFPAGE..1
(-7300 3925);
FORCEPROP 2 LAST $XR0 268 
J 0
(-7552 3925);
DISPLAY 0.638298 (-7552 3925);
PAINT MONO (-7552 3925);
FORCEPROP 2 LAST CDS_LIB standard
J 0
(-7300 3925);
DISPLAY INVISIBLE (-7300 3925);
FORCEPROP 1 LAST OFFPAGE TRUE
J 0
(-6975 3800);
DISPLAY 0.872340 (-6975 3800);
PAINT GREEN (-6975 3800);
DISPLAY INVISIBLE (-6975 3800);
FORCEPROP 1 LAST COMMENT_BODY TRUE
J 0
(-7175 3825);
DISPLAY 0.872340 (-7175 3825);
PAINT GREEN (-7175 3825);
DISPLAY INVISIBLE (-7175 3825);
FORCEPROP 2 LAST PATH I173
J 0
(-7250 4000);
DISPLAY 0.680851 (-7250 4000);
DISPLAY INVISIBLE (-7250 4000);
FORCEADD OFFPAGE..1
R 2
(-2150 5875);
FORCEPROP 2 LAST $XR0 359 
J 0
(-1964 5875);
DISPLAY 0.638298 (-1964 5875);
PAINT MONO (-1964 5875);
FORCEPROP 2 LAST CDS_LIB standard
J 0
(-2150 5875);
DISPLAY INVISIBLE (-2150 5875);
FORCEPROP 1 LAST OFFPAGE TRUE
J 2
(-2475 5750);
DISPLAY 0.872340 (-2475 5750);
PAINT GREEN (-2475 5750);
DISPLAY INVISIBLE (-2475 5750);
FORCEPROP 1 LAST COMMENT_BODY TRUE
J 2
(-2275 5775);
DISPLAY 0.872340 (-2275 5775);
PAINT GREEN (-2275 5775);
DISPLAY INVISIBLE (-2275 5775);
FORCEPROP 2 LAST PATH I174
J 0
(-1975 5950);
DISPLAY 0.680851 (-1975 5950);
DISPLAY INVISIBLE (-1975 5950);
FORCEADD OFFPAGE..1
R 2
(-2150 5625);
FORCEPROP 2 LAST $XR0 359 
J 0
(-1964 5625);
DISPLAY 0.638298 (-1964 5625);
PAINT MONO (-1964 5625);
FORCEPROP 2 LAST CDS_LIB standard
J 0
(-2150 5625);
DISPLAY INVISIBLE (-2150 5625);
FORCEPROP 1 LAST OFFPAGE TRUE
J 2
(-2475 5500);
DISPLAY 0.872340 (-2475 5500);
PAINT GREEN (-2475 5500);
DISPLAY INVISIBLE (-2475 5500);
FORCEPROP 1 LAST COMMENT_BODY TRUE
J 2
(-2275 5525);
DISPLAY 0.872340 (-2275 5525);
PAINT GREEN (-2275 5525);
DISPLAY INVISIBLE (-2275 5525);
FORCEPROP 2 LAST PATH I175
J 0
(-1975 5700);
DISPLAY 0.680851 (-1975 5700);
DISPLAY INVISIBLE (-1975 5700);
FORCEADD Q_RES..1
(-3225 4775);
FORCEPROP 1 LAST LOCATION R1340
J 0
(-3100 4775);
DISPLAY 0.489362 (-3100 4775);
PAINT SKYBLUE (-3100 4775);
FORCEPROP 0 LAST $SEC 1
J 0
(-3100 4800);
DISPLAY 0.680851 (-3100 4800);
PAINT MONO (-3100 4800);
DISPLAY INVISIBLE (-3100 4800);
FORCEPROP 0 LAST CDS_SEC 1
J 0
(-3100 4800);
DISPLAY 0.680851 (-3100 4800);
DISPLAY INVISIBLE (-3100 4800);
FORCEPROP 1 LASTPIN (-3325 4775) $PN 1
J 0
(-3313 4787);
DISPLAY 0.787234 (-3313 4787);
PAINT MONO (-3313 4787);
FORCEPROP 1 LASTPIN (-3125 4775) $PN 2
J 0
(-3163 4787);
DISPLAY 0.787234 (-3163 4787);
PAINT MONO (-3163 4787);
FORCEPROP 1 LAST VALUE 0
J 2
(-3350 4775);
DISPLAY 0.489362 (-3350 4775);
PAINT SKYBLUE (-3350 4775);
FORCEPROP 2 LAST CDS_LIB pure_quanta
J 0
(-3225 4775);
DISPLAY INVISIBLE (-3225 4775);
FORCEPROP 2 LAST BOM_COST MEM
J 2
(-3200 4925);
DISPLAY 0.744681 (-3200 4925);
PAINT WHITE (-3200 4925);
DISPLAY INVISIBLE (-3200 4925);
FORCEPROP 1 LAST WATTAGE 1/16W
J 2
(-3300 4700);
DISPLAY 0.489362 (-3300 4700);
PAINT SKYBLUE (-3300 4700);
DISPLAY INVISIBLE (-3300 4700);
FORCEPROP 1 LAST MATERIAL CHIP
J 2
(-3050 4750);
DISPLAY 0.489362 (-3050 4750);
PAINT SKYBLUE (-3050 4750);
DISPLAY INVISIBLE (-3050 4750);
FORCEPROP 1 LAST TOLERANCE 5%
J 0
(-3350 4750);
DISPLAY 0.489362 (-3350 4750);
PAINT SKYBLUE (-3350 4750);
DISPLAY INVISIBLE (-3350 4750);
FORCEPROP 1 LAST PACK_TYPE 0402LF
J 2
(-3050 4700);
DISPLAY 0.489362 (-3050 4700);
PAINT SKYBLUE (-3050 4700);
DISPLAY INVISIBLE (-3050 4700);
FORCEPROP 1 LAST PATH I176
J 0
(-3275 4925);
DISPLAY 0.978723 (-3275 4925);
PAINT WHITE (-3275 4925);
DISPLAY INVISIBLE (-3275 4925);
FORCEPROP 1 LAST PART_NUMBER CS00002JB13
J 2
(-3125 4825);
DISPLAY 0.489362 (-3125 4825);
PAINT SKYBLUE (-3125 4825);
DISPLAY INVISIBLE (-3125 4825);
FORCEADD OFFPAGE..1
R 2
(-2350 4775);
FORCEPROP 2 LAST $XR1 358 
J 0
(-2014 4775);
DISPLAY 0.638298 (-2014 4775);
PAINT MONO (-2014 4775);
FORCEPROP 2 LAST $XR0 237 
J 0
(-2134 4775);
DISPLAY 0.638298 (-2134 4775);
PAINT MONO (-2134 4775);
FORCEPROP 2 LAST CDS_LIB standard
J 0
(-2350 4775);
DISPLAY INVISIBLE (-2350 4775);
FORCEPROP 1 LAST OFFPAGE TRUE
J 2
(-2675 4650);
DISPLAY 0.872340 (-2675 4650);
PAINT GREEN (-2675 4650);
DISPLAY INVISIBLE (-2675 4650);
FORCEPROP 1 LAST COMMENT_BODY TRUE
J 2
(-2475 4675);
DISPLAY 0.872340 (-2475 4675);
PAINT GREEN (-2475 4675);
DISPLAY INVISIBLE (-2475 4675);
FORCEPROP 2 LAST PATH I177
J 0
(-2175 4850);
DISPLAY 0.680851 (-2175 4850);
DISPLAY INVISIBLE (-2175 4850);
FORCEADD Q_RES..1
(-6350 3875);
FORCEPROP 1 LAST LOCATION R1329
J 0
(-6225 3875);
DISPLAY 0.489362 (-6225 3875);
PAINT SKYBLUE (-6225 3875);
FORCEPROP 0 LAST $SEC 1
J 0
(-6225 3900);
DISPLAY 0.680851 (-6225 3900);
PAINT MONO (-6225 3900);
DISPLAY INVISIBLE (-6225 3900);
FORCEPROP 0 LAST CDS_SEC 1
J 0
(-6225 3900);
DISPLAY 0.680851 (-6225 3900);
DISPLAY INVISIBLE (-6225 3900);
FORCEPROP 1 LASTPIN (-6450 3875) $PN 1
J 0
(-6438 3887);
DISPLAY 0.787234 (-6438 3887);
PAINT MONO (-6438 3887);
FORCEPROP 1 LASTPIN (-6250 3875) $PN 2
J 0
(-6288 3887);
DISPLAY 0.787234 (-6288 3887);
PAINT MONO (-6288 3887);
FORCEPROP 1 LAST VALUE 0
J 2
(-6475 3875);
DISPLAY 0.489362 (-6475 3875);
PAINT SKYBLUE (-6475 3875);
FORCEPROP 2 LAST CDS_LIB pure_quanta
J 0
(-6350 3875);
DISPLAY INVISIBLE (-6350 3875);
FORCEPROP 2 LAST BOM_COST MEM
J 2
(-6325 4025);
DISPLAY 0.744681 (-6325 4025);
PAINT WHITE (-6325 4025);
DISPLAY INVISIBLE (-6325 4025);
FORCEPROP 1 LAST WATTAGE 1/16W
J 2
(-6425 3800);
DISPLAY 0.489362 (-6425 3800);
PAINT SKYBLUE (-6425 3800);
DISPLAY INVISIBLE (-6425 3800);
FORCEPROP 1 LAST MATERIAL CHIP
J 2
(-6175 3850);
DISPLAY 0.489362 (-6175 3850);
PAINT SKYBLUE (-6175 3850);
DISPLAY INVISIBLE (-6175 3850);
FORCEPROP 1 LAST TOLERANCE 5%
J 0
(-6475 3850);
DISPLAY 0.489362 (-6475 3850);
PAINT SKYBLUE (-6475 3850);
DISPLAY INVISIBLE (-6475 3850);
FORCEPROP 1 LAST PACK_TYPE 0402LF
J 2
(-6175 3800);
DISPLAY 0.489362 (-6175 3800);
PAINT SKYBLUE (-6175 3800);
DISPLAY INVISIBLE (-6175 3800);
FORCEPROP 1 LAST PATH I178
J 0
(-6400 4025);
DISPLAY 0.978723 (-6400 4025);
PAINT WHITE (-6400 4025);
DISPLAY INVISIBLE (-6400 4025);
FORCEPROP 1 LAST PART_NUMBER CS00002JB13
J 2
(-6250 3925);
DISPLAY 0.489362 (-6250 3925);
PAINT SKYBLUE (-6250 3925);
DISPLAY INVISIBLE (-6250 3925);
FORCEADD OFFPAGE..1
(-7300 3875);
FORCEPROP 2 LAST $XR1 358 
J 0
(-7672 3875);
DISPLAY 0.638298 (-7672 3875);
PAINT MONO (-7672 3875);
FORCEPROP 2 LAST $XR0 237 
J 0
(-7552 3875);
DISPLAY 0.638298 (-7552 3875);
PAINT MONO (-7552 3875);
FORCEPROP 2 LAST CDS_LIB standard
J 0
(-7300 3875);
DISPLAY INVISIBLE (-7300 3875);
FORCEPROP 1 LAST OFFPAGE TRUE
J 0
(-6975 3750);
DISPLAY 0.872340 (-6975 3750);
PAINT GREEN (-6975 3750);
DISPLAY INVISIBLE (-6975 3750);
FORCEPROP 1 LAST COMMENT_BODY TRUE
J 0
(-7175 3775);
DISPLAY 0.872340 (-7175 3775);
PAINT GREEN (-7175 3775);
DISPLAY INVISIBLE (-7175 3775);
FORCEPROP 2 LAST PATH I179
J 0
(-7250 3950);
DISPLAY 0.680851 (-7250 3950);
DISPLAY INVISIBLE (-7250 3950);
FORCEADD OFFPAGE..1
(-7300 4725);
FORCEPROP 2 LAST $XR0 54 
J 0
(-7521 4725);
DISPLAY 0.638298 (-7521 4725);
PAINT MONO (-7521 4725);
FORCEPROP 2 LAST CDS_LIB standard
J 0
(-7300 4725);
DISPLAY INVISIBLE (-7300 4725);
FORCEPROP 1 LAST OFFPAGE TRUE
J 0
(-6975 4600);
DISPLAY 0.872340 (-6975 4600);
PAINT GREEN (-6975 4600);
DISPLAY INVISIBLE (-6975 4600);
FORCEPROP 1 LAST COMMENT_BODY TRUE
J 0
(-7175 4625);
DISPLAY 0.872340 (-7175 4625);
PAINT GREEN (-7175 4625);
DISPLAY INVISIBLE (-7175 4625);
FORCEPROP 2 LAST PATH I18
J 0
(-7500 4775);
DISPLAY 0.680851 (-7500 4775);
DISPLAY INVISIBLE (-7500 4775);
FORCEADD Q_RES..1
R 2
(-3275 3775);
FORCEPROP 1 LAST LOCATION R1339
J 2
(-3375 3775);
DISPLAY 0.489362 (-3375 3775);
PAINT SKYBLUE (-3375 3775);
FORCEPROP 0 LAST $SEC 1
J 0
(-3150 3800);
DISPLAY 0.680851 (-3150 3800);
PAINT MONO (-3150 3800);
DISPLAY INVISIBLE (-3150 3800);
FORCEPROP 0 LAST CDS_SEC 1
J 0
(-3150 3800);
DISPLAY 0.680851 (-3150 3800);
DISPLAY INVISIBLE (-3150 3800);
FORCEPROP 1 LASTPIN (-3175 3775) $PN 1
J 2
(-3187 3787);
DISPLAY 0.787234 (-3187 3787);
PAINT MONO (-3187 3787);
FORCEPROP 1 LASTPIN (-3375 3775) $PN 2
J 2
(-3337 3787);
DISPLAY 0.787234 (-3337 3787);
PAINT MONO (-3337 3787);
FORCEPROP 1 LAST VALUE 0
J 0
(-3150 3775);
DISPLAY 0.489362 (-3150 3775);
PAINT SKYBLUE (-3150 3775);
FORCEPROP 2 LAST BOM_COST MEM
J 0
(-3300 3925);
DISPLAY 0.744681 (-3300 3925);
PAINT WHITE (-3300 3925);
DISPLAY INVISIBLE (-3300 3925);
FORCEPROP 1 LAST WATTAGE 1/16W
J 0
(-3200 3700);
DISPLAY 0.489362 (-3200 3700);
PAINT SKYBLUE (-3200 3700);
DISPLAY INVISIBLE (-3200 3700);
FORCEPROP 1 LAST MATERIAL CHIP
J 0
(-3450 3750);
DISPLAY 0.489362 (-3450 3750);
PAINT SKYBLUE (-3450 3750);
DISPLAY INVISIBLE (-3450 3750);
FORCEPROP 1 LAST TOLERANCE 5%
J 2
(-3150 3750);
DISPLAY 0.489362 (-3150 3750);
PAINT SKYBLUE (-3150 3750);
DISPLAY INVISIBLE (-3150 3750);
FORCEPROP 1 LAST PACK_TYPE 0402LF
J 0
(-3450 3700);
DISPLAY 0.489362 (-3450 3700);
PAINT SKYBLUE (-3450 3700);
DISPLAY INVISIBLE (-3450 3700);
FORCEPROP 2 LAST CDS_LIB pure_quanta
J 0
(-3275 3775);
DISPLAY INVISIBLE (-3275 3775);
FORCEPROP 1 LAST PATH I180
J 2
(-3225 3925);
DISPLAY 0.978723 (-3225 3925);
PAINT WHITE (-3225 3925);
DISPLAY INVISIBLE (-3225 3925);
FORCEPROP 1 LAST PART_NUMBER CS00002JB13
J 0
(-3375 3825);
DISPLAY 0.489362 (-3375 3825);
PAINT SKYBLUE (-3375 3825);
DISPLAY INVISIBLE (-3375 3825);
FORCEADD OFFPAGE..1
R 2
(-2325 3775);
FORCEPROP 2 LAST $XR1 358 
J 0
(-2019 3775);
DISPLAY 0.638298 (-2019 3775);
PAINT MONO (-2019 3775);
FORCEPROP 2 LAST $XR0 238 
J 0
(-2139 3775);
DISPLAY 0.638298 (-2139 3775);
PAINT MONO (-2139 3775);
FORCEPROP 2 LAST CDS_LIB standard
J 0
(-2325 3775);
DISPLAY INVISIBLE (-2325 3775);
FORCEPROP 1 LAST OFFPAGE TRUE
J 2
(-2650 3650);
DISPLAY 0.872340 (-2650 3650);
PAINT GREEN (-2650 3650);
DISPLAY INVISIBLE (-2650 3650);
FORCEPROP 1 LAST COMMENT_BODY TRUE
J 2
(-2450 3675);
DISPLAY 0.872340 (-2450 3675);
PAINT GREEN (-2450 3675);
DISPLAY INVISIBLE (-2450 3675);
FORCEPROP 2 LAST PATH I181
J 0
(-2150 3850);
DISPLAY 0.680851 (-2150 3850);
DISPLAY INVISIBLE (-2150 3850);
FORCEADD OFFPAGE..1
(-7300 5475);
FORCEPROP 2 LAST $XR0 55 
J 0
(-7551 5475);
DISPLAY 0.638298 (-7551 5475);
PAINT MONO (-7551 5475);
FORCEPROP 2 LAST CDS_LIB standard
J 0
(-7300 5475);
DISPLAY INVISIBLE (-7300 5475);
FORCEPROP 1 LAST OFFPAGE TRUE
J 0
(-6975 5350);
DISPLAY 0.872340 (-6975 5350);
PAINT GREEN (-6975 5350);
DISPLAY INVISIBLE (-6975 5350);
FORCEPROP 1 LAST COMMENT_BODY TRUE
J 0
(-7175 5375);
DISPLAY 0.872340 (-7175 5375);
PAINT GREEN (-7175 5375);
DISPLAY INVISIBLE (-7175 5375);
FORCEPROP 2 LAST PATH I182
J 0
(-7250 5550);
DISPLAY 0.680851 (-7250 5550);
DISPLAY INVISIBLE (-7250 5550);
FORCEADD OFFPAGE..1
(-7300 4825);
FORCEPROP 2 LAST $XR0 98 
J 0
(-7521 4825);
DISPLAY 0.638298 (-7521 4825);
PAINT MONO (-7521 4825);
FORCEPROP 2 LAST CDS_LIB standard
J 0
(-7300 4825);
DISPLAY INVISIBLE (-7300 4825);
FORCEPROP 1 LAST OFFPAGE TRUE
J 0
(-6975 4700);
DISPLAY 0.872340 (-6975 4700);
PAINT GREEN (-6975 4700);
DISPLAY INVISIBLE (-6975 4700);
FORCEPROP 1 LAST COMMENT_BODY TRUE
J 0
(-7175 4725);
DISPLAY 0.872340 (-7175 4725);
PAINT GREEN (-7175 4725);
DISPLAY INVISIBLE (-7175 4725);
FORCEPROP 2 LAST PATH I19
J 0
(-7500 4875);
DISPLAY 0.680851 (-7500 4875);
DISPLAY INVISIBLE (-7500 4875);
FORCEADD GND..1
(-6200 250);
FORCEPROP 3 LASTPIN (-6200 300) SIG_NAME GND\g
J 0
(-6190 310);
DISPLAY 0.659574 (-6190 310);
PAINT MONO (-6190 310);
DISPLAY INVISIBLE (-6190 310);
FORCEPROP 2 LAST CDS_LIB pure_quanta_power
J 0
(-6200 250);
DISPLAY INVISIBLE (-6200 250);
FORCEPROP 1 LAST SIZE 1B
J 0
(-6125 200);
DISPLAY 0.851064 (-6125 200);
PAINT GREEN (-6125 200);
DISPLAY INVISIBLE (-6125 200);
FORCEPROP 1 LAST HDL_POWER GND
J 0
(-6200 400);
DISPLAY 0.851064 (-6200 400);
PAINT GREEN (-6200 400);
DISPLAY INVISIBLE (-6200 400);
FORCEPROP 1 LAST PATH I2
J 0
(-6125 250);
DISPLAY 0.872340 (-6125 250);
PAINT AQUA (-6125 250);
DISPLAY INVISIBLE (-6125 250);
FORCEADD OFFPAGE..1
(-7300 4925);
FORCEPROP 2 LAST $XR0 54 
J 0
(-7521 4925);
DISPLAY 0.638298 (-7521 4925);
PAINT MONO (-7521 4925);
FORCEPROP 2 LAST CDS_LIB standard
J 0
(-7300 4925);
DISPLAY INVISIBLE (-7300 4925);
FORCEPROP 1 LAST OFFPAGE TRUE
J 0
(-6975 4800);
DISPLAY 0.872340 (-6975 4800);
PAINT GREEN (-6975 4800);
DISPLAY INVISIBLE (-6975 4800);
FORCEPROP 1 LAST COMMENT_BODY TRUE
J 0
(-7175 4825);
DISPLAY 0.872340 (-7175 4825);
PAINT GREEN (-7175 4825);
DISPLAY INVISIBLE (-7175 4825);
FORCEPROP 2 LAST PATH I20
J 0
(-7500 4975);
DISPLAY 0.680851 (-7500 4975);
DISPLAY INVISIBLE (-7500 4975);
FORCEADD OFFPAGE..1
(-7300 4875);
FORCEPROP 2 LAST $XR0 200 
J 0
(-7552 4875);
DISPLAY 0.638298 (-7552 4875);
PAINT MONO (-7552 4875);
FORCEPROP 2 LAST CDS_LIB standard
J 0
(-7300 4875);
DISPLAY INVISIBLE (-7300 4875);
FORCEPROP 1 LAST OFFPAGE TRUE
J 0
(-6975 4750);
DISPLAY 0.872340 (-6975 4750);
PAINT GREEN (-6975 4750);
DISPLAY INVISIBLE (-6975 4750);
FORCEPROP 1 LAST COMMENT_BODY TRUE
J 0
(-7175 4775);
DISPLAY 0.872340 (-7175 4775);
PAINT GREEN (-7175 4775);
DISPLAY INVISIBLE (-7175 4775);
FORCEPROP 2 LAST PATH I21
J 0
(-7550 4925);
DISPLAY 0.680851 (-7550 4925);
DISPLAY INVISIBLE (-7550 4925);
FORCEADD OFFPAGE..1
(-7300 4975);
FORCEPROP 2 LAST $XR0 54 
J 0
(-7551 4975);
DISPLAY 0.638298 (-7551 4975);
PAINT MONO (-7551 4975);
FORCEPROP 2 LAST CDS_LIB standard
J 0
(-7300 4975);
DISPLAY INVISIBLE (-7300 4975);
FORCEPROP 1 LAST OFFPAGE TRUE
J 0
(-6975 4850);
DISPLAY 0.872340 (-6975 4850);
PAINT GREEN (-6975 4850);
DISPLAY INVISIBLE (-6975 4850);
FORCEPROP 1 LAST COMMENT_BODY TRUE
J 0
(-7175 4875);
DISPLAY 0.872340 (-7175 4875);
PAINT GREEN (-7175 4875);
DISPLAY INVISIBLE (-7175 4875);
FORCEPROP 2 LAST PATH I22
J 0
(-7500 5025);
DISPLAY 0.680851 (-7500 5025);
DISPLAY INVISIBLE (-7500 5025);
FORCEADD OFFPAGE..5
(-7300 4675);
FORCEPROP 2 LAST $XR0 200 
J 0
(-7585 4675);
DISPLAY 0.638298 (-7585 4675);
PAINT MONO (-7585 4675);
FORCEPROP 2 LAST CDS_LIB standard
J 0
(-7300 4675);
DISPLAY INVISIBLE (-7300 4675);
FORCEPROP 1 LAST OFFPAGE TRUE
J 0
(-6975 4550);
DISPLAY 0.872340 (-6975 4550);
PAINT GREEN (-6975 4550);
DISPLAY INVISIBLE (-6975 4550);
FORCEPROP 1 LAST COMMENT_BODY TRUE
J 0
(-7200 4600);
DISPLAY 0.872340 (-7200 4600);
PAINT GREEN (-7200 4600);
DISPLAY INVISIBLE (-7200 4600);
FORCEPROP 2 LAST PATH I23
J 0
(-7575 4725);
DISPLAY 0.680851 (-7575 4725);
DISPLAY INVISIBLE (-7575 4725);
FORCEADD OFFPAGE..1
(-7300 5075);
FORCEPROP 2 LAST $XR0 104 
J 0
(-7552 5075);
DISPLAY 0.638298 (-7552 5075);
PAINT MONO (-7552 5075);
FORCEPROP 2 LAST CDS_LIB standard
J 0
(-7300 5075);
DISPLAY INVISIBLE (-7300 5075);
FORCEPROP 1 LAST OFFPAGE TRUE
J 0
(-6975 4950);
DISPLAY 0.872340 (-6975 4950);
PAINT GREEN (-6975 4950);
DISPLAY INVISIBLE (-6975 4950);
FORCEPROP 1 LAST COMMENT_BODY TRUE
J 0
(-7175 4975);
DISPLAY 0.872340 (-7175 4975);
PAINT GREEN (-7175 4975);
DISPLAY INVISIBLE (-7175 4975);
FORCEPROP 2 LAST PATH I24
J 0
(-7550 5125);
DISPLAY 0.680851 (-7550 5125);
DISPLAY INVISIBLE (-7550 5125);
FORCEADD OFFPAGE..1
(-7300 5275);
FORCEPROP 2 LAST $XR0 193 
J 0
(-7582 5275);
DISPLAY 0.638298 (-7582 5275);
PAINT MONO (-7582 5275);
FORCEPROP 2 LAST CDS_LIB standard
J 0
(-7300 5275);
DISPLAY INVISIBLE (-7300 5275);
FORCEPROP 1 LAST OFFPAGE TRUE
J 0
(-6975 5150);
DISPLAY 0.872340 (-6975 5150);
PAINT GREEN (-6975 5150);
DISPLAY INVISIBLE (-6975 5150);
FORCEPROP 1 LAST COMMENT_BODY TRUE
J 0
(-7175 5175);
DISPLAY 0.872340 (-7175 5175);
PAINT GREEN (-7175 5175);
DISPLAY INVISIBLE (-7175 5175);
FORCEPROP 2 LAST PATH I25
J 0
(-7600 5325);
DISPLAY 0.680851 (-7600 5325);
DISPLAY INVISIBLE (-7600 5325);
FORCEADD OFFPAGE..1
(-7300 5175);
FORCEPROP 2 LAST $XR0 217 
J 0
(-7552 5175);
DISPLAY 0.638298 (-7552 5175);
PAINT MONO (-7552 5175);
FORCEPROP 2 LAST CDS_LIB standard
J 0
(-7300 5175);
DISPLAY INVISIBLE (-7300 5175);
FORCEPROP 1 LAST OFFPAGE TRUE
J 0
(-6975 5050);
DISPLAY 0.872340 (-6975 5050);
PAINT GREEN (-6975 5050);
DISPLAY INVISIBLE (-6975 5050);
FORCEPROP 1 LAST COMMENT_BODY TRUE
J 0
(-7175 5075);
DISPLAY 0.872340 (-7175 5075);
PAINT GREEN (-7175 5075);
DISPLAY INVISIBLE (-7175 5075);
FORCEPROP 2 LAST PATH I26
J 0
(-7550 5225);
DISPLAY 0.680851 (-7550 5225);
DISPLAY INVISIBLE (-7550 5225);
FORCEADD OFFPAGE..1
(-7300 5225);
FORCEPROP 2 LAST $XR0 200 
J 0
(-7552 5225);
DISPLAY 0.638298 (-7552 5225);
PAINT MONO (-7552 5225);
FORCEPROP 2 LAST CDS_LIB standard
J 0
(-7300 5225);
DISPLAY INVISIBLE (-7300 5225);
FORCEPROP 1 LAST OFFPAGE TRUE
J 0
(-6975 5100);
DISPLAY 0.872340 (-6975 5100);
PAINT GREEN (-6975 5100);
DISPLAY INVISIBLE (-6975 5100);
FORCEPROP 1 LAST COMMENT_BODY TRUE
J 0
(-7175 5125);
DISPLAY 0.872340 (-7175 5125);
PAINT GREEN (-7175 5125);
DISPLAY INVISIBLE (-7175 5125);
FORCEPROP 2 LAST PATH I27
J 0
(-7550 5275);
DISPLAY 0.680851 (-7550 5275);
DISPLAY INVISIBLE (-7550 5275);
FORCEADD OFFPAGE..5
(-7300 5325);
FORCEPROP 2 LAST $XR0 55 
J 0
(-7554 5325);
DISPLAY 0.638298 (-7554 5325);
PAINT MONO (-7554 5325);
FORCEPROP 2 LAST CDS_LIB standard
J 0
(-7300 5325);
DISPLAY INVISIBLE (-7300 5325);
FORCEPROP 1 LAST OFFPAGE TRUE
J 0
(-6975 5200);
DISPLAY 0.872340 (-6975 5200);
DISPLAY INVISIBLE (-6975 5200);
FORCEPROP 1 LAST COMMENT_BODY TRUE
J 0
(-7200 5250);
DISPLAY 0.872340 (-7200 5250);
PAINT GREEN (-7200 5250);
DISPLAY INVISIBLE (-7200 5250);
FORCEPROP 2 LAST PATH I28
J 0
(-7575 5375);
DISPLAY 0.680851 (-7575 5375);
DISPLAY INVISIBLE (-7575 5375);
FORCEADD OFFPAGE..5
(-7300 5375);
FORCEPROP 2 LAST $XR0 55 
J 0
(-7554 5375);
DISPLAY 0.638298 (-7554 5375);
PAINT MONO (-7554 5375);
FORCEPROP 2 LAST CDS_LIB standard
J 0
(-7300 5375);
DISPLAY INVISIBLE (-7300 5375);
FORCEPROP 1 LAST OFFPAGE TRUE
J 0
(-6975 5250);
DISPLAY 0.872340 (-6975 5250);
DISPLAY INVISIBLE (-6975 5250);
FORCEPROP 1 LAST COMMENT_BODY TRUE
J 0
(-7200 5300);
DISPLAY 0.872340 (-7200 5300);
PAINT GREEN (-7200 5300);
DISPLAY INVISIBLE (-7200 5300);
FORCEPROP 2 LAST PATH I29
J 0
(-7575 5425);
DISPLAY 0.680851 (-7575 5425);
DISPLAY INVISIBLE (-7575 5425);
FORCEADD OFFPAGE..1
(-7300 3675);
FORCEPROP 2 LAST $XR1 200 
J 0
(-7641 3675);
DISPLAY 0.638298 (-7641 3675);
PAINT MONO (-7641 3675);
FORCEPROP 2 LAST $XR0 83 
J 0
(-7521 3675);
DISPLAY 0.638298 (-7521 3675);
PAINT MONO (-7521 3675);
FORCEPROP 2 LAST CDS_LIB standard
J 0
(-7300 3675);
DISPLAY INVISIBLE (-7300 3675);
FORCEPROP 1 LAST OFFPAGE TRUE
J 0
(-6975 3550);
DISPLAY 0.872340 (-6975 3550);
PAINT GREEN (-6975 3550);
DISPLAY INVISIBLE (-6975 3550);
FORCEPROP 1 LAST COMMENT_BODY TRUE
J 0
(-7175 3575);
DISPLAY 0.872340 (-7175 3575);
PAINT GREEN (-7175 3575);
DISPLAY INVISIBLE (-7175 3575);
FORCEPROP 2 LAST PATH I3
J 0
(-7500 3725);
DISPLAY 0.680851 (-7500 3725);
DISPLAY INVISIBLE (-7500 3725);
FORCEADD OFFPAGE..6
(-7300 5425);
FORCEPROP 2 LAST $XR1 172 
J 0
(-7669 5425);
DISPLAY 0.638298 (-7669 5425);
PAINT MONO (-7669 5425);
FORCEPROP 2 LAST $XR0 27 
J 0
(-7549 5425);
DISPLAY 0.638298 (-7549 5425);
PAINT MONO (-7549 5425);
FORCEPROP 2 LAST CDS_LIB standard
J 0
(-7300 5425);
DISPLAY INVISIBLE (-7300 5425);
FORCEPROP 1 LAST OFFPAGE TRUE
J 0
(-6975 5300);
DISPLAY 0.872340 (-6975 5300);
PAINT GREEN (-6975 5300);
DISPLAY INVISIBLE (-6975 5300);
FORCEPROP 1 LAST COMMENT_BODY TRUE
J 0
(-7200 5350);
DISPLAY 0.872340 (-7200 5350);
PAINT GREEN (-7200 5350);
DISPLAY INVISIBLE (-7200 5350);
FORCEPROP 2 LAST PATH I30
J 0
(-7575 5475);
DISPLAY 0.680851 (-7575 5475);
DISPLAY INVISIBLE (-7575 5475);
FORCEADD OFFPAGE..6
(-7300 5575);
FORCEPROP 2 LAST $XR0 28 
J 0
(-7549 5575);
DISPLAY 0.638298 (-7549 5575);
PAINT MONO (-7549 5575);
FORCEPROP 2 LAST CDS_LIB standard
J 0
(-7300 5575);
DISPLAY INVISIBLE (-7300 5575);
FORCEPROP 1 LAST OFFPAGE TRUE
J 0
(-6975 5450);
DISPLAY 0.872340 (-6975 5450);
PAINT GREEN (-6975 5450);
DISPLAY INVISIBLE (-6975 5450);
FORCEPROP 1 LAST COMMENT_BODY TRUE
J 0
(-7200 5500);
DISPLAY 0.872340 (-7200 5500);
PAINT GREEN (-7200 5500);
DISPLAY INVISIBLE (-7200 5500);
FORCEPROP 2 LAST PATH I32
J 0
(-7575 5625);
DISPLAY 0.680851 (-7575 5625);
DISPLAY INVISIBLE (-7575 5625);
FORCEADD OFFPAGE..2
R 2
(-7300 5525);
FORCEPROP 2 LAST $XR0 28 
J 0
(-7554 5525);
DISPLAY 0.638298 (-7554 5525);
PAINT MONO (-7554 5525);
FORCEPROP 2 LAST CDS_LIB standard
J 2
(-7300 5525);
DISPLAY INVISIBLE (-7300 5525);
FORCEPROP 1 LAST OFFPAGE TRUE
J 2
(-7625 5400);
DISPLAY 0.872340 (-7625 5400);
DISPLAY INVISIBLE (-7625 5400);
FORCEPROP 1 LAST COMMENT_BODY TRUE
J 2
(-7255 5430);
DISPLAY 0.872340 (-7255 5430);
PAINT GREEN (-7255 5430);
DISPLAY INVISIBLE (-7255 5430);
FORCEPROP 2 LAST PATH I33
J 2
(-7025 5575);
DISPLAY 0.680851 (-7025 5575);
DISPLAY INVISIBLE (-7025 5575);
FORCEADD OFFPAGE..6
(-7300 5675);
FORCEPROP 2 LAST $XR0 27 
J 0
(-7549 5675);
DISPLAY 0.638298 (-7549 5675);
PAINT MONO (-7549 5675);
FORCEPROP 2 LAST CDS_LIB standard
J 0
(-7300 5675);
DISPLAY INVISIBLE (-7300 5675);
FORCEPROP 1 LAST OFFPAGE TRUE
J 0
(-6975 5550);
DISPLAY 0.872340 (-6975 5550);
PAINT GREEN (-6975 5550);
DISPLAY INVISIBLE (-6975 5550);
FORCEPROP 1 LAST COMMENT_BODY TRUE
J 0
(-7200 5600);
DISPLAY 0.872340 (-7200 5600);
PAINT GREEN (-7200 5600);
DISPLAY INVISIBLE (-7200 5600);
FORCEPROP 2 LAST PATH I34
J 0
(-7575 5725);
DISPLAY 0.680851 (-7575 5725);
DISPLAY INVISIBLE (-7575 5725);
FORCEADD OFFPAGE..6
(-7300 5625);
FORCEPROP 2 LAST $XR0 28 
J 0
(-7549 5625);
DISPLAY 0.638298 (-7549 5625);
PAINT MONO (-7549 5625);
FORCEPROP 2 LAST CDS_LIB standard
J 0
(-7300 5625);
DISPLAY INVISIBLE (-7300 5625);
FORCEPROP 1 LAST OFFPAGE TRUE
J 0
(-6975 5500);
DISPLAY 0.872340 (-6975 5500);
PAINT GREEN (-6975 5500);
DISPLAY INVISIBLE (-6975 5500);
FORCEPROP 1 LAST COMMENT_BODY TRUE
J 0
(-7200 5550);
DISPLAY 0.872340 (-7200 5550);
PAINT GREEN (-7200 5550);
DISPLAY INVISIBLE (-7200 5550);
FORCEPROP 2 LAST PATH I35
J 0
(-7575 5675);
DISPLAY 0.680851 (-7575 5675);
DISPLAY INVISIBLE (-7575 5675);
FORCEADD OFFPAGE..6
(-7300 5725);
FORCEPROP 2 LAST $XR1 172 
J 0
(-7669 5725);
DISPLAY 0.638298 (-7669 5725);
PAINT MONO (-7669 5725);
FORCEPROP 2 LAST $XR0 27 
J 0
(-7549 5725);
DISPLAY 0.638298 (-7549 5725);
PAINT MONO (-7549 5725);
FORCEPROP 2 LAST CDS_LIB standard
J 0
(-7300 5725);
DISPLAY INVISIBLE (-7300 5725);
FORCEPROP 1 LAST OFFPAGE TRUE
J 0
(-6975 5600);
DISPLAY 0.872340 (-6975 5600);
PAINT GREEN (-6975 5600);
DISPLAY INVISIBLE (-6975 5600);
FORCEPROP 1 LAST COMMENT_BODY TRUE
J 0
(-7200 5650);
DISPLAY 0.872340 (-7200 5650);
PAINT GREEN (-7200 5650);
DISPLAY INVISIBLE (-7200 5650);
FORCEPROP 2 LAST PATH I36
J 0
(-7575 5775);
DISPLAY 0.680851 (-7575 5775);
DISPLAY INVISIBLE (-7575 5775);
FORCEADD OFFPAGE..6
(-7300 5825);
FORCEPROP 2 LAST $XR1 54 
J 0
(-7639 5825);
DISPLAY 0.638298 (-7639 5825);
PAINT MONO (-7639 5825);
FORCEPROP 2 LAST $XR0 27 
J 0
(-7549 5825);
DISPLAY 0.638298 (-7549 5825);
PAINT MONO (-7549 5825);
FORCEPROP 2 LAST CDS_LIB standard
J 0
(-7300 5825);
DISPLAY INVISIBLE (-7300 5825);
FORCEPROP 1 LAST OFFPAGE TRUE
J 0
(-6975 5700);
DISPLAY 0.872340 (-6975 5700);
PAINT GREEN (-6975 5700);
DISPLAY INVISIBLE (-6975 5700);
FORCEPROP 1 LAST COMMENT_BODY TRUE
J 0
(-7200 5750);
DISPLAY 0.872340 (-7200 5750);
PAINT GREEN (-7200 5750);
DISPLAY INVISIBLE (-7200 5750);
FORCEPROP 2 LAST PATH I37
J 0
(-7575 5875);
DISPLAY 0.680851 (-7575 5875);
DISPLAY INVISIBLE (-7575 5875);
FORCEADD OFFPAGE..5
(-7300 5775);
FORCEPROP 2 LAST $XR0 55 
J 0
(-7554 5775);
DISPLAY 0.638298 (-7554 5775);
PAINT MONO (-7554 5775);
FORCEPROP 2 LAST CDS_LIB standard
J 0
(-7300 5775);
DISPLAY INVISIBLE (-7300 5775);
FORCEPROP 1 LAST OFFPAGE TRUE
J 0
(-6975 5650);
DISPLAY 0.872340 (-6975 5650);
DISPLAY INVISIBLE (-6975 5650);
FORCEPROP 1 LAST COMMENT_BODY TRUE
J 0
(-7200 5700);
DISPLAY 0.872340 (-7200 5700);
PAINT GREEN (-7200 5700);
DISPLAY INVISIBLE (-7200 5700);
FORCEPROP 2 LAST PATH I38
J 0
(-7575 5825);
DISPLAY 0.680851 (-7575 5825);
DISPLAY INVISIBLE (-7575 5825);
FORCEADD OFFPAGE..6
(-7300 5875);
FORCEPROP 2 LAST $XR0 28 
J 0
(-7549 5875);
DISPLAY 0.638298 (-7549 5875);
PAINT MONO (-7549 5875);
FORCEPROP 2 LAST CDS_LIB standard
J 0
(-7300 5875);
DISPLAY INVISIBLE (-7300 5875);
FORCEPROP 1 LAST OFFPAGE TRUE
J 0
(-6975 5750);
DISPLAY 0.872340 (-6975 5750);
PAINT GREEN (-6975 5750);
DISPLAY INVISIBLE (-6975 5750);
FORCEPROP 1 LAST COMMENT_BODY TRUE
J 0
(-7200 5800);
DISPLAY 0.872340 (-7200 5800);
PAINT GREEN (-7200 5800);
DISPLAY INVISIBLE (-7200 5800);
FORCEPROP 2 LAST PATH I39
J 0
(-7575 5925);
DISPLAY 0.680851 (-7575 5925);
DISPLAY INVISIBLE (-7575 5925);
FORCEADD OFFPAGE..1
(-7300 3725);
FORCEPROP 2 LAST $XR1 217 
J 0
(-7671 3725);
DISPLAY 0.638298 (-7671 3725);
PAINT MONO (-7671 3725);
FORCEPROP 2 LAST $XR0 83 
J 0
(-7551 3725);
DISPLAY 0.638298 (-7551 3725);
PAINT MONO (-7551 3725);
FORCEPROP 2 LAST CDS_LIB standard
J 0
(-7300 3725);
DISPLAY INVISIBLE (-7300 3725);
FORCEPROP 1 LAST OFFPAGE TRUE
J 0
(-6975 3600);
DISPLAY 0.872340 (-6975 3600);
PAINT GREEN (-6975 3600);
DISPLAY INVISIBLE (-6975 3600);
FORCEPROP 1 LAST COMMENT_BODY TRUE
J 0
(-7175 3625);
DISPLAY 0.872340 (-7175 3625);
PAINT GREEN (-7175 3625);
DISPLAY INVISIBLE (-7175 3625);
FORCEPROP 2 LAST PATH I4
J 0
(-7500 3775);
DISPLAY 0.680851 (-7500 3775);
DISPLAY INVISIBLE (-7500 3775);
FORCEADD OFFPAGE..6
(-7300 5925);
FORCEPROP 2 LAST $XR1 172 
J 0
(-7669 5925);
DISPLAY 0.638298 (-7669 5925);
PAINT MONO (-7669 5925);
FORCEPROP 2 LAST $XR0 27 
J 0
(-7549 5925);
DISPLAY 0.638298 (-7549 5925);
PAINT MONO (-7549 5925);
FORCEPROP 2 LAST CDS_LIB standard
J 0
(-7300 5925);
DISPLAY INVISIBLE (-7300 5925);
FORCEPROP 1 LAST OFFPAGE TRUE
J 0
(-6975 5800);
DISPLAY 0.872340 (-6975 5800);
PAINT GREEN (-6975 5800);
DISPLAY INVISIBLE (-6975 5800);
FORCEPROP 1 LAST COMMENT_BODY TRUE
J 0
(-7200 5850);
DISPLAY 0.872340 (-7200 5850);
PAINT GREEN (-7200 5850);
DISPLAY INVISIBLE (-7200 5850);
FORCEPROP 2 LAST PATH I40
J 0
(-7575 5975);
DISPLAY 0.680851 (-7575 5975);
DISPLAY INVISIBLE (-7575 5975);
FORCEADD OFFPAGE..6
(-7300 6025);
FORCEPROP 2 LAST $XR1 54 
J 0
(-7639 6025);
DISPLAY 0.638298 (-7639 6025);
PAINT MONO (-7639 6025);
FORCEPROP 2 LAST $XR0 27 
J 0
(-7549 6025);
DISPLAY 0.638298 (-7549 6025);
PAINT MONO (-7549 6025);
FORCEPROP 2 LAST CDS_LIB standard
J 0
(-7300 6025);
DISPLAY INVISIBLE (-7300 6025);
FORCEPROP 1 LAST OFFPAGE TRUE
J 0
(-6975 5900);
DISPLAY 0.872340 (-6975 5900);
PAINT GREEN (-6975 5900);
DISPLAY INVISIBLE (-6975 5900);
FORCEPROP 1 LAST COMMENT_BODY TRUE
J 0
(-7200 5950);
DISPLAY 0.872340 (-7200 5950);
PAINT GREEN (-7200 5950);
DISPLAY INVISIBLE (-7200 5950);
FORCEPROP 2 LAST PATH I41
J 0
(-7575 6075);
DISPLAY 0.680851 (-7575 6075);
DISPLAY INVISIBLE (-7575 6075);
FORCEADD OFFPAGE..6
(-7300 6075);
FORCEPROP 2 LAST $XR1 54 
J 0
(-7639 6075);
DISPLAY 0.638298 (-7639 6075);
PAINT MONO (-7639 6075);
FORCEPROP 2 LAST $XR0 27 
J 0
(-7549 6075);
DISPLAY 0.638298 (-7549 6075);
PAINT MONO (-7549 6075);
FORCEPROP 2 LAST CDS_LIB standard
J 0
(-7300 6075);
DISPLAY INVISIBLE (-7300 6075);
FORCEPROP 1 LAST OFFPAGE TRUE
J 0
(-6975 5950);
DISPLAY 0.872340 (-6975 5950);
PAINT GREEN (-6975 5950);
DISPLAY INVISIBLE (-6975 5950);
FORCEPROP 1 LAST COMMENT_BODY TRUE
J 0
(-7200 6000);
DISPLAY 0.872340 (-7200 6000);
PAINT GREEN (-7200 6000);
DISPLAY INVISIBLE (-7200 6000);
FORCEPROP 2 LAST PATH I42
J 0
(-7575 6125);
DISPLAY 0.680851 (-7575 6125);
DISPLAY INVISIBLE (-7575 6125);
FORCEADD OFFPAGE..5
(-7300 5975);
FORCEPROP 2 LAST $XR0 54 
J 0
(-7554 5975);
DISPLAY 0.638298 (-7554 5975);
PAINT MONO (-7554 5975);
FORCEPROP 2 LAST CDS_LIB standard
J 0
(-7300 5975);
DISPLAY INVISIBLE (-7300 5975);
FORCEPROP 1 LAST OFFPAGE TRUE
J 0
(-6975 5850);
DISPLAY 0.872340 (-6975 5850);
PAINT GREEN (-6975 5850);
DISPLAY INVISIBLE (-6975 5850);
FORCEPROP 1 LAST COMMENT_BODY TRUE
J 0
(-7200 5900);
DISPLAY 0.872340 (-7200 5900);
PAINT GREEN (-7200 5900);
DISPLAY INVISIBLE (-7200 5900);
FORCEPROP 2 LAST PATH I43
J 0
(-7550 6025);
DISPLAY 0.680851 (-7550 6025);
DISPLAY INVISIBLE (-7550 6025);
FORCEADD Q_RES..1
(-6450 4125);
FORCEPROP 1 LAST LOCATION R262
J 0
(-6325 4125);
DISPLAY 0.489362 (-6325 4125);
PAINT SKYBLUE (-6325 4125);
FORCEPROP 0 LAST $SEC 1
J 2
(-6325 4175);
DISPLAY 0.680851 (-6325 4175);
PAINT MONO (-6325 4175);
DISPLAY INVISIBLE (-6325 4175);
FORCEPROP 0 LAST CDS_SEC 1
J 2
(-6325 4175);
DISPLAY 1.021277 (-6325 4175);
DISPLAY INVISIBLE (-6325 4175);
FORCEPROP 1 LASTPIN (-6550 4125) $PN 1
J 0
(-6538 4137);
DISPLAY 0.489362 (-6538 4137);
PAINT MONO (-6538 4137);
FORCEPROP 1 LASTPIN (-6350 4125) $PN 2
J 0
(-6388 4137);
DISPLAY 0.489362 (-6388 4137);
PAINT MONO (-6388 4137);
FORCEPROP 1 LAST VALUE 0
J 2
(-6575 4125);
DISPLAY 0.489362 (-6575 4125);
PAINT SKYBLUE (-6575 4125);
FORCEPROP 2 LAST CDS_LIB pure_quanta
J 2
(-6450 4125);
DISPLAY INVISIBLE (-6450 4125);
FORCEPROP 1 LAST PACK_TYPE 0402LF
J 2
(-6275 4050);
DISPLAY 0.489362 (-6275 4050);
PAINT SKYBLUE (-6275 4050);
DISPLAY INVISIBLE (-6275 4050);
FORCEPROP 1 LAST TOLERANCE 5%
J 0
(-6575 4100);
DISPLAY 0.489362 (-6575 4100);
PAINT SKYBLUE (-6575 4100);
DISPLAY INVISIBLE (-6575 4100);
FORCEPROP 1 LAST MATERIAL CHIP
J 2
(-6275 4100);
DISPLAY 0.489362 (-6275 4100);
PAINT SKYBLUE (-6275 4100);
DISPLAY INVISIBLE (-6275 4100);
FORCEPROP 1 LAST WATTAGE 1/16W
J 2
(-6525 4050);
DISPLAY 0.489362 (-6525 4050);
PAINT SKYBLUE (-6525 4050);
DISPLAY INVISIBLE (-6525 4050);
FORCEPROP 2 LAST BOM_COST MEM
J 2
(-6425 4275);
DISPLAY 0.744681 (-6425 4275);
PAINT WHITE (-6425 4275);
DISPLAY INVISIBLE (-6425 4275);
FORCEPROP 1 LAST PATH I44
J 0
(-6500 4275);
DISPLAY 0.978723 (-6500 4275);
PAINT WHITE (-6500 4275);
DISPLAY INVISIBLE (-6500 4275);
FORCEPROP 1 LAST PART_NUMBER CS00002JB13
J 2
(-6350 4175);
DISPLAY 0.489362 (-6350 4175);
PAINT SKYBLUE (-6350 4175);
DISPLAY INVISIBLE (-6350 4175);
FORCEADD Q_RES..1
(-6450 4175);
FORCEPROP 1 LAST LOCATION R180
J 0
(-6325 4175);
DISPLAY 0.489362 (-6325 4175);
PAINT SKYBLUE (-6325 4175);
FORCEPROP 0 LAST $SEC 1
J 0
(-6325 4225);
DISPLAY 0.680851 (-6325 4225);
PAINT MONO (-6325 4225);
DISPLAY INVISIBLE (-6325 4225);
FORCEPROP 0 LAST CDS_SEC 1
J 0
(-6325 4225);
DISPLAY 1.021277 (-6325 4225);
DISPLAY INVISIBLE (-6325 4225);
FORCEPROP 1 LASTPIN (-6550 4175) $PN 1
J 0
(-6538 4187);
DISPLAY 0.489362 (-6538 4187);
PAINT MONO (-6538 4187);
FORCEPROP 1 LASTPIN (-6350 4175) $PN 2
J 0
(-6388 4187);
DISPLAY 0.489362 (-6388 4187);
PAINT MONO (-6388 4187);
FORCEPROP 1 LAST VALUE 0
J 2
(-6575 4175);
DISPLAY 0.489362 (-6575 4175);
PAINT SKYBLUE (-6575 4175);
FORCEPROP 2 LAST CDS_LIB pure_quanta
J 0
(-6450 4175);
DISPLAY INVISIBLE (-6450 4175);
FORCEPROP 2 LAST BOM_COST MEM
J 2
(-6425 4325);
DISPLAY 0.744681 (-6425 4325);
PAINT WHITE (-6425 4325);
DISPLAY INVISIBLE (-6425 4325);
FORCEPROP 1 LAST WATTAGE 1/16W
J 2
(-6525 4100);
DISPLAY 0.489362 (-6525 4100);
PAINT SKYBLUE (-6525 4100);
DISPLAY INVISIBLE (-6525 4100);
FORCEPROP 1 LAST MATERIAL CHIP
J 2
(-6275 4150);
DISPLAY 0.489362 (-6275 4150);
PAINT SKYBLUE (-6275 4150);
DISPLAY INVISIBLE (-6275 4150);
FORCEPROP 1 LAST TOLERANCE 5%
J 0
(-6575 4150);
DISPLAY 0.489362 (-6575 4150);
PAINT SKYBLUE (-6575 4150);
DISPLAY INVISIBLE (-6575 4150);
FORCEPROP 1 LAST PACK_TYPE 0402LF
J 2
(-6275 4100);
DISPLAY 0.489362 (-6275 4100);
PAINT SKYBLUE (-6275 4100);
DISPLAY INVISIBLE (-6275 4100);
FORCEPROP 1 LAST PATH I45
J 0
(-6500 4325);
DISPLAY 0.978723 (-6500 4325);
PAINT WHITE (-6500 4325);
DISPLAY INVISIBLE (-6500 4325);
FORCEPROP 1 LAST PART_NUMBER CS00002JB13
J 2
(-6350 4225);
DISPLAY 0.489362 (-6350 4225);
PAINT SKYBLUE (-6350 4225);
DISPLAY INVISIBLE (-6350 4225);
FORCEADD Q_RES..1
(-6450 4225);
FORCEPROP 1 LAST LOCATION R181
J 0
(-6325 4225);
DISPLAY 0.489362 (-6325 4225);
PAINT SKYBLUE (-6325 4225);
FORCEPROP 0 LAST $SEC 1
J 0
(-6325 4275);
DISPLAY 0.680851 (-6325 4275);
PAINT MONO (-6325 4275);
DISPLAY INVISIBLE (-6325 4275);
FORCEPROP 0 LAST CDS_SEC 1
J 0
(-6325 4275);
DISPLAY 1.021277 (-6325 4275);
DISPLAY INVISIBLE (-6325 4275);
FORCEPROP 1 LASTPIN (-6550 4225) $PN 1
J 0
(-6538 4237);
DISPLAY 0.489362 (-6538 4237);
PAINT MONO (-6538 4237);
FORCEPROP 1 LASTPIN (-6350 4225) $PN 2
J 0
(-6388 4237);
DISPLAY 0.489362 (-6388 4237);
PAINT MONO (-6388 4237);
FORCEPROP 1 LAST VALUE 0
J 2
(-6575 4225);
DISPLAY 0.489362 (-6575 4225);
PAINT SKYBLUE (-6575 4225);
FORCEPROP 2 LAST CDS_LIB pure_quanta
J 0
(-6450 4225);
DISPLAY INVISIBLE (-6450 4225);
FORCEPROP 2 LAST BOM_COST MEM
J 2
(-6425 4375);
DISPLAY 0.744681 (-6425 4375);
PAINT WHITE (-6425 4375);
DISPLAY INVISIBLE (-6425 4375);
FORCEPROP 1 LAST WATTAGE 1/16W
J 2
(-6525 4150);
DISPLAY 0.489362 (-6525 4150);
PAINT SKYBLUE (-6525 4150);
DISPLAY INVISIBLE (-6525 4150);
FORCEPROP 1 LAST MATERIAL CHIP
J 2
(-6275 4200);
DISPLAY 0.489362 (-6275 4200);
PAINT SKYBLUE (-6275 4200);
DISPLAY INVISIBLE (-6275 4200);
FORCEPROP 1 LAST TOLERANCE 5%
J 0
(-6575 4200);
DISPLAY 0.489362 (-6575 4200);
PAINT SKYBLUE (-6575 4200);
DISPLAY INVISIBLE (-6575 4200);
FORCEPROP 1 LAST PACK_TYPE 0402LF
J 2
(-6275 4150);
DISPLAY 0.489362 (-6275 4150);
PAINT SKYBLUE (-6275 4150);
DISPLAY INVISIBLE (-6275 4150);
FORCEPROP 1 LAST PATH I46
J 0
(-6500 4375);
DISPLAY 0.978723 (-6500 4375);
PAINT WHITE (-6500 4375);
DISPLAY INVISIBLE (-6500 4375);
FORCEPROP 1 LAST PART_NUMBER CS00002JB13
J 2
(-6350 4275);
DISPLAY 0.489362 (-6350 4275);
PAINT SKYBLUE (-6350 4275);
DISPLAY INVISIBLE (-6350 4275);
FORCEADD Q_RES..1
(-6450 4375);
FORCEPROP 1 LAST LOCATION R263
J 0
(-6325 4375);
DISPLAY 0.489362 (-6325 4375);
PAINT SKYBLUE (-6325 4375);
FORCEPROP 0 LAST $SEC 1
J 2
(-6325 4425);
DISPLAY 0.680851 (-6325 4425);
PAINT MONO (-6325 4425);
DISPLAY INVISIBLE (-6325 4425);
FORCEPROP 0 LAST CDS_SEC 1
J 2
(-6325 4425);
DISPLAY 1.021277 (-6325 4425);
DISPLAY INVISIBLE (-6325 4425);
FORCEPROP 1 LASTPIN (-6550 4375) $PN 1
J 0
(-6538 4387);
DISPLAY 0.489362 (-6538 4387);
PAINT MONO (-6538 4387);
FORCEPROP 1 LASTPIN (-6350 4375) $PN 2
J 0
(-6388 4387);
DISPLAY 0.489362 (-6388 4387);
PAINT MONO (-6388 4387);
FORCEPROP 1 LAST VALUE 0
J 2
(-6575 4375);
DISPLAY 0.489362 (-6575 4375);
PAINT SKYBLUE (-6575 4375);
FORCEPROP 2 LAST BOM_COST MEM
J 2
(-6425 4525);
DISPLAY 0.744681 (-6425 4525);
PAINT WHITE (-6425 4525);
DISPLAY INVISIBLE (-6425 4525);
FORCEPROP 2 LAST CDS_LIB pure_quanta
J 2
(-6450 4375);
DISPLAY INVISIBLE (-6450 4375);
FORCEPROP 1 LAST WATTAGE 1/16W
J 2
(-6525 4300);
DISPLAY 0.489362 (-6525 4300);
PAINT SKYBLUE (-6525 4300);
DISPLAY INVISIBLE (-6525 4300);
FORCEPROP 1 LAST MATERIAL CHIP
J 2
(-6275 4350);
DISPLAY 0.489362 (-6275 4350);
PAINT SKYBLUE (-6275 4350);
DISPLAY INVISIBLE (-6275 4350);
FORCEPROP 1 LAST TOLERANCE 5%
J 0
(-6575 4350);
DISPLAY 0.489362 (-6575 4350);
PAINT SKYBLUE (-6575 4350);
DISPLAY INVISIBLE (-6575 4350);
FORCEPROP 1 LAST PACK_TYPE 0402LF
J 2
(-6275 4300);
DISPLAY 0.489362 (-6275 4300);
PAINT SKYBLUE (-6275 4300);
DISPLAY INVISIBLE (-6275 4300);
FORCEPROP 1 LAST PATH I47
J 0
(-6500 4525);
DISPLAY 0.978723 (-6500 4525);
PAINT WHITE (-6500 4525);
DISPLAY INVISIBLE (-6500 4525);
FORCEPROP 1 LAST PART_NUMBER CS00002JB13
J 2
(-6350 4425);
DISPLAY 0.489362 (-6350 4425);
PAINT SKYBLUE (-6350 4425);
DISPLAY INVISIBLE (-6350 4425);
FORCEADD Q_RES..1
(-6450 4325);
FORCEPROP 1 LAST LOCATION R184
J 0
(-6325 4325);
DISPLAY 0.489362 (-6325 4325);
PAINT SKYBLUE (-6325 4325);
FORCEPROP 0 LAST $SEC 1
J 2
(-6325 4375);
DISPLAY 0.680851 (-6325 4375);
PAINT MONO (-6325 4375);
DISPLAY INVISIBLE (-6325 4375);
FORCEPROP 0 LAST CDS_SEC 1
J 2
(-6325 4375);
DISPLAY 1.021277 (-6325 4375);
DISPLAY INVISIBLE (-6325 4375);
FORCEPROP 1 LASTPIN (-6550 4325) $PN 1
J 0
(-6538 4337);
DISPLAY 0.489362 (-6538 4337);
PAINT MONO (-6538 4337);
FORCEPROP 1 LASTPIN (-6350 4325) $PN 2
J 0
(-6388 4337);
DISPLAY 0.489362 (-6388 4337);
PAINT MONO (-6388 4337);
FORCEPROP 1 LAST VALUE 0
J 2
(-6575 4325);
DISPLAY 0.489362 (-6575 4325);
PAINT SKYBLUE (-6575 4325);
FORCEPROP 2 LAST CDS_LIB pure_quanta
J 2
(-6450 4325);
DISPLAY INVISIBLE (-6450 4325);
FORCEPROP 2 LAST BOM_COST MEM
J 2
(-6425 4475);
DISPLAY 0.744681 (-6425 4475);
PAINT WHITE (-6425 4475);
DISPLAY INVISIBLE (-6425 4475);
FORCEPROP 1 LAST WATTAGE 1/16W
J 2
(-6525 4250);
DISPLAY 0.489362 (-6525 4250);
PAINT SKYBLUE (-6525 4250);
DISPLAY INVISIBLE (-6525 4250);
FORCEPROP 1 LAST MATERIAL CHIP
J 2
(-6275 4300);
DISPLAY 0.489362 (-6275 4300);
PAINT SKYBLUE (-6275 4300);
DISPLAY INVISIBLE (-6275 4300);
FORCEPROP 1 LAST TOLERANCE 5%
J 0
(-6575 4300);
DISPLAY 0.489362 (-6575 4300);
PAINT SKYBLUE (-6575 4300);
DISPLAY INVISIBLE (-6575 4300);
FORCEPROP 1 LAST PACK_TYPE 0402LF
J 2
(-6275 4250);
DISPLAY 0.489362 (-6275 4250);
PAINT SKYBLUE (-6275 4250);
DISPLAY INVISIBLE (-6275 4250);
FORCEPROP 1 LAST PATH I48
J 0
(-6500 4475);
DISPLAY 0.978723 (-6500 4475);
PAINT WHITE (-6500 4475);
DISPLAY INVISIBLE (-6500 4475);
FORCEPROP 1 LAST PART_NUMBER CS00002JB13
J 2
(-6350 4375);
DISPLAY 0.489362 (-6350 4375);
PAINT SKYBLUE (-6350 4375);
DISPLAY INVISIBLE (-6350 4375);
FORCEADD Q_RES..1
(-6450 4525);
FORCEPROP 1 LAST LOCATION R260
J 0
(-6325 4525);
DISPLAY 0.489362 (-6325 4525);
PAINT SKYBLUE (-6325 4525);
FORCEPROP 0 LAST $SEC 1
J 2
(-6325 4575);
DISPLAY 0.680851 (-6325 4575);
PAINT MONO (-6325 4575);
DISPLAY INVISIBLE (-6325 4575);
FORCEPROP 0 LAST CDS_SEC 1
J 2
(-6325 4575);
DISPLAY 1.021277 (-6325 4575);
DISPLAY INVISIBLE (-6325 4575);
FORCEPROP 1 LASTPIN (-6550 4525) $PN 1
J 0
(-6538 4537);
DISPLAY 0.489362 (-6538 4537);
PAINT MONO (-6538 4537);
FORCEPROP 1 LASTPIN (-6350 4525) $PN 2
J 0
(-6388 4537);
DISPLAY 0.489362 (-6388 4537);
PAINT MONO (-6388 4537);
FORCEPROP 1 LAST VALUE 0
J 2
(-6575 4525);
DISPLAY 0.489362 (-6575 4525);
PAINT SKYBLUE (-6575 4525);
FORCEPROP 2 LAST CDS_LIB pure_quanta
J 2
(-6450 4525);
DISPLAY INVISIBLE (-6450 4525);
FORCEPROP 2 LAST BOM_COST MEM
J 2
(-6425 4675);
DISPLAY 0.744681 (-6425 4675);
PAINT WHITE (-6425 4675);
DISPLAY INVISIBLE (-6425 4675);
FORCEPROP 1 LAST WATTAGE 1/16W
J 2
(-6525 4450);
DISPLAY 0.489362 (-6525 4450);
PAINT SKYBLUE (-6525 4450);
DISPLAY INVISIBLE (-6525 4450);
FORCEPROP 1 LAST MATERIAL CHIP
J 2
(-6275 4500);
DISPLAY 0.489362 (-6275 4500);
PAINT SKYBLUE (-6275 4500);
DISPLAY INVISIBLE (-6275 4500);
FORCEPROP 1 LAST TOLERANCE 5%
J 0
(-6575 4500);
DISPLAY 0.489362 (-6575 4500);
PAINT SKYBLUE (-6575 4500);
DISPLAY INVISIBLE (-6575 4500);
FORCEPROP 1 LAST PACK_TYPE 0402LF
J 2
(-6275 4450);
DISPLAY 0.489362 (-6275 4450);
PAINT SKYBLUE (-6275 4450);
DISPLAY INVISIBLE (-6275 4450);
FORCEPROP 1 LAST PATH I49
J 0
(-6500 4675);
DISPLAY 0.978723 (-6500 4675);
PAINT WHITE (-6500 4675);
DISPLAY INVISIBLE (-6500 4675);
FORCEPROP 1 LAST PART_NUMBER CS00002JB13
J 2
(-6350 4575);
DISPLAY 0.489362 (-6350 4575);
PAINT SKYBLUE (-6350 4575);
DISPLAY INVISIBLE (-6350 4575);
FORCEADD OFFPAGE..1
(-7300 3575);
FORCEPROP 2 LAST $XR1 152 
J 0
(-7672 3575);
DISPLAY 0.638298 (-7672 3575);
PAINT MONO (-7672 3575);
FORCEPROP 2 LAST $XR0 150 
J 0
(-7552 3575);
DISPLAY 0.638298 (-7552 3575);
PAINT MONO (-7552 3575);
FORCEPROP 2 LAST CDS_LIB standard
J 0
(-7300 3575);
DISPLAY INVISIBLE (-7300 3575);
FORCEPROP 1 LAST OFFPAGE TRUE
J 0
(-6975 3450);
DISPLAY 0.872340 (-6975 3450);
PAINT GREEN (-6975 3450);
DISPLAY INVISIBLE (-6975 3450);
FORCEPROP 1 LAST COMMENT_BODY TRUE
J 0
(-7175 3475);
DISPLAY 0.872340 (-7175 3475);
PAINT GREEN (-7175 3475);
DISPLAY INVISIBLE (-7175 3475);
FORCEPROP 2 LAST PATH I5
J 0
(-7550 3625);
DISPLAY 0.680851 (-7550 3625);
DISPLAY INVISIBLE (-7550 3625);
FORCEADD Q_RES..1
(-6450 4575);
FORCEPROP 1 LAST LOCATION R261
J 0
(-6325 4575);
DISPLAY 0.489362 (-6325 4575);
PAINT SKYBLUE (-6325 4575);
FORCEPROP 0 LAST $SEC 1
J 2
(-6325 4625);
DISPLAY 0.680851 (-6325 4625);
PAINT MONO (-6325 4625);
DISPLAY INVISIBLE (-6325 4625);
FORCEPROP 0 LAST CDS_SEC 1
J 2
(-6325 4625);
DISPLAY 1.021277 (-6325 4625);
DISPLAY INVISIBLE (-6325 4625);
FORCEPROP 1 LASTPIN (-6550 4575) $PN 1
J 0
(-6538 4587);
DISPLAY 0.489362 (-6538 4587);
PAINT MONO (-6538 4587);
FORCEPROP 1 LASTPIN (-6350 4575) $PN 2
J 0
(-6388 4587);
DISPLAY 0.489362 (-6388 4587);
PAINT MONO (-6388 4587);
FORCEPROP 1 LAST VALUE 0
J 2
(-6575 4575);
DISPLAY 0.489362 (-6575 4575);
PAINT SKYBLUE (-6575 4575);
FORCEPROP 2 LAST CDS_LIB pure_quanta
J 2
(-6450 4575);
DISPLAY INVISIBLE (-6450 4575);
FORCEPROP 2 LAST BOM_COST MEM
J 2
(-6425 4725);
DISPLAY 0.744681 (-6425 4725);
PAINT WHITE (-6425 4725);
DISPLAY INVISIBLE (-6425 4725);
FORCEPROP 1 LAST WATTAGE 1/16W
J 2
(-6525 4500);
DISPLAY 0.489362 (-6525 4500);
PAINT SKYBLUE (-6525 4500);
DISPLAY INVISIBLE (-6525 4500);
FORCEPROP 1 LAST MATERIAL CHIP
J 2
(-6275 4550);
DISPLAY 0.489362 (-6275 4550);
PAINT SKYBLUE (-6275 4550);
DISPLAY INVISIBLE (-6275 4550);
FORCEPROP 1 LAST TOLERANCE 5%
J 0
(-6575 4550);
DISPLAY 0.489362 (-6575 4550);
PAINT SKYBLUE (-6575 4550);
DISPLAY INVISIBLE (-6575 4550);
FORCEPROP 1 LAST PACK_TYPE 0402LF
J 2
(-6275 4500);
DISPLAY 0.489362 (-6275 4500);
PAINT SKYBLUE (-6275 4500);
DISPLAY INVISIBLE (-6275 4500);
FORCEPROP 1 LAST PATH I50
J 0
(-6500 4725);
DISPLAY 0.978723 (-6500 4725);
PAINT WHITE (-6500 4725);
DISPLAY INVISIBLE (-6500 4725);
FORCEPROP 1 LAST PART_NUMBER CS00002JB13
J 2
(-6350 4625);
DISPLAY 0.489362 (-6350 4625);
PAINT SKYBLUE (-6350 4625);
DISPLAY INVISIBLE (-6350 4625);
FORCEADD Q_RES..1
(-6450 4675);
FORCEPROP 1 LAST LOCATION R232
J 0
(-6325 4675);
DISPLAY 0.489362 (-6325 4675);
PAINT SKYBLUE (-6325 4675);
FORCEPROP 0 LAST $SEC 1
J 2
(-6325 4725);
DISPLAY 0.680851 (-6325 4725);
PAINT MONO (-6325 4725);
DISPLAY INVISIBLE (-6325 4725);
FORCEPROP 0 LAST CDS_SEC 1
J 2
(-6325 4725);
DISPLAY 1.021277 (-6325 4725);
DISPLAY INVISIBLE (-6325 4725);
FORCEPROP 1 LASTPIN (-6550 4675) $PN 1
J 0
(-6538 4687);
DISPLAY 0.489362 (-6538 4687);
PAINT MONO (-6538 4687);
FORCEPROP 1 LASTPIN (-6350 4675) $PN 2
J 0
(-6388 4687);
DISPLAY 0.489362 (-6388 4687);
PAINT MONO (-6388 4687);
FORCEPROP 1 LAST VALUE 33
J 2
(-6575 4675);
DISPLAY 0.489362 (-6575 4675);
PAINT SKYBLUE (-6575 4675);
FORCEPROP 2 LAST CDS_LIB pure_quanta
J 2
(-6450 4675);
DISPLAY INVISIBLE (-6450 4675);
FORCEPROP 2 LAST BOM_COST MEM
J 2
(-6425 4825);
DISPLAY 0.744681 (-6425 4825);
PAINT WHITE (-6425 4825);
DISPLAY INVISIBLE (-6425 4825);
FORCEPROP 1 LAST WATTAGE 1/16W
J 2
(-6525 4600);
DISPLAY 0.489362 (-6525 4600);
PAINT SKYBLUE (-6525 4600);
DISPLAY INVISIBLE (-6525 4600);
FORCEPROP 1 LAST MATERIAL CHIP
J 2
(-6275 4650);
DISPLAY 0.489362 (-6275 4650);
PAINT SKYBLUE (-6275 4650);
DISPLAY INVISIBLE (-6275 4650);
FORCEPROP 1 LAST TOLERANCE 5%
J 0
(-6575 4650);
DISPLAY 0.489362 (-6575 4650);
PAINT SKYBLUE (-6575 4650);
DISPLAY INVISIBLE (-6575 4650);
FORCEPROP 1 LAST PACK_TYPE 0402LF
J 2
(-6275 4600);
DISPLAY 0.489362 (-6275 4600);
PAINT SKYBLUE (-6275 4600);
DISPLAY INVISIBLE (-6275 4600);
FORCEPROP 1 LAST PATH I51
J 0
(-6500 4825);
DISPLAY 0.978723 (-6500 4825);
PAINT WHITE (-6500 4825);
DISPLAY INVISIBLE (-6500 4825);
FORCEPROP 1 LAST PART_NUMBER CS03302JB10
J 2
(-6350 4725);
DISPLAY 0.489362 (-6350 4725);
PAINT SKYBLUE (-6350 4725);
DISPLAY INVISIBLE (-6350 4725);
FORCEADD Q_RES..1
(-6450 4775);
FORCEPROP 1 LAST LOCATION R222
J 0
(-6325 4775);
DISPLAY 0.489362 (-6325 4775);
PAINT SKYBLUE (-6325 4775);
FORCEPROP 0 LAST $SEC 1
J 0
(-6325 4825);
DISPLAY 0.680851 (-6325 4825);
PAINT MONO (-6325 4825);
DISPLAY INVISIBLE (-6325 4825);
FORCEPROP 0 LAST CDS_SEC 1
J 0
(-6325 4825);
DISPLAY 1.021277 (-6325 4825);
DISPLAY INVISIBLE (-6325 4825);
FORCEPROP 1 LASTPIN (-6550 4775) $PN 1
J 0
(-6538 4787);
DISPLAY 0.489362 (-6538 4787);
PAINT MONO (-6538 4787);
FORCEPROP 1 LASTPIN (-6350 4775) $PN 2
J 0
(-6388 4787);
DISPLAY 0.489362 (-6388 4787);
PAINT MONO (-6388 4787);
FORCEPROP 1 LAST VALUE 0
J 2
(-6575 4775);
DISPLAY 0.489362 (-6575 4775);
PAINT SKYBLUE (-6575 4775);
FORCEPROP 2 LAST BOM_COST MEM
J 2
(-6425 4925);
DISPLAY 0.744681 (-6425 4925);
PAINT WHITE (-6425 4925);
DISPLAY INVISIBLE (-6425 4925);
FORCEPROP 2 LAST CDS_LIB pure_quanta
J 2
(-6450 4775);
DISPLAY INVISIBLE (-6450 4775);
FORCEPROP 1 LAST WATTAGE 1/16W
J 2
(-6525 4700);
DISPLAY 0.489362 (-6525 4700);
PAINT SKYBLUE (-6525 4700);
DISPLAY INVISIBLE (-6525 4700);
FORCEPROP 1 LAST MATERIAL CHIP
J 2
(-6275 4750);
DISPLAY 0.489362 (-6275 4750);
PAINT SKYBLUE (-6275 4750);
DISPLAY INVISIBLE (-6275 4750);
FORCEPROP 1 LAST TOLERANCE 5%
J 0
(-6575 4750);
DISPLAY 0.489362 (-6575 4750);
PAINT SKYBLUE (-6575 4750);
DISPLAY INVISIBLE (-6575 4750);
FORCEPROP 1 LAST PACK_TYPE 0402LF
J 2
(-6275 4700);
DISPLAY 0.489362 (-6275 4700);
PAINT SKYBLUE (-6275 4700);
DISPLAY INVISIBLE (-6275 4700);
FORCEPROP 1 LAST PATH I52
J 0
(-6500 4925);
DISPLAY 0.978723 (-6500 4925);
PAINT WHITE (-6500 4925);
DISPLAY INVISIBLE (-6500 4925);
FORCEPROP 1 LAST PART_NUMBER CS00002JB13
J 2
(-6350 4825);
DISPLAY 0.489362 (-6350 4825);
PAINT SKYBLUE (-6350 4825);
DISPLAY INVISIBLE (-6350 4825);
FORCEADD Q_RES..1
(-6450 4725);
FORCEPROP 1 LAST LOCATION R264
J 0
(-6325 4725);
DISPLAY 0.489362 (-6325 4725);
PAINT SKYBLUE (-6325 4725);
FORCEPROP 0 LAST $SEC 1
J 2
(-6325 4775);
DISPLAY 0.680851 (-6325 4775);
PAINT MONO (-6325 4775);
DISPLAY INVISIBLE (-6325 4775);
FORCEPROP 0 LAST CDS_SEC 1
J 2
(-6325 4775);
DISPLAY 1.021277 (-6325 4775);
DISPLAY INVISIBLE (-6325 4775);
FORCEPROP 1 LASTPIN (-6550 4725) $PN 1
J 0
(-6538 4737);
DISPLAY 0.489362 (-6538 4737);
PAINT MONO (-6538 4737);
FORCEPROP 1 LASTPIN (-6350 4725) $PN 2
J 0
(-6388 4737);
DISPLAY 0.489362 (-6388 4737);
PAINT MONO (-6388 4737);
FORCEPROP 1 LAST VALUE 0
J 2
(-6575 4725);
DISPLAY 0.489362 (-6575 4725);
PAINT SKYBLUE (-6575 4725);
FORCEPROP 2 LAST CDS_LIB pure_quanta
J 2
(-6450 4725);
DISPLAY INVISIBLE (-6450 4725);
FORCEPROP 2 LAST BOM_COST MEM
J 2
(-6425 4875);
DISPLAY 0.744681 (-6425 4875);
PAINT WHITE (-6425 4875);
DISPLAY INVISIBLE (-6425 4875);
FORCEPROP 1 LAST WATTAGE 1/16W
J 2
(-6525 4650);
DISPLAY 0.489362 (-6525 4650);
PAINT SKYBLUE (-6525 4650);
DISPLAY INVISIBLE (-6525 4650);
FORCEPROP 1 LAST MATERIAL CHIP
J 2
(-6275 4700);
DISPLAY 0.489362 (-6275 4700);
PAINT SKYBLUE (-6275 4700);
DISPLAY INVISIBLE (-6275 4700);
FORCEPROP 1 LAST TOLERANCE 5%
J 0
(-6575 4700);
DISPLAY 0.489362 (-6575 4700);
PAINT SKYBLUE (-6575 4700);
DISPLAY INVISIBLE (-6575 4700);
FORCEPROP 1 LAST PACK_TYPE 0402LF
J 2
(-6275 4650);
DISPLAY 0.489362 (-6275 4650);
PAINT SKYBLUE (-6275 4650);
DISPLAY INVISIBLE (-6275 4650);
FORCEPROP 1 LAST PATH I53
J 0
(-6500 4875);
DISPLAY 0.978723 (-6500 4875);
PAINT WHITE (-6500 4875);
DISPLAY INVISIBLE (-6500 4875);
FORCEPROP 1 LAST PART_NUMBER CS00002JB13
J 2
(-6350 4775);
DISPLAY 0.489362 (-6350 4775);
PAINT SKYBLUE (-6350 4775);
DISPLAY INVISIBLE (-6350 4775);
FORCEADD Q_RES..1
(-6450 4875);
FORCEPROP 1 LAST LOCATION R233
J 0
(-6325 4875);
DISPLAY 0.489362 (-6325 4875);
PAINT SKYBLUE (-6325 4875);
FORCEPROP 0 LAST $SEC 1
J 0
(-6325 4925);
DISPLAY 0.680851 (-6325 4925);
PAINT MONO (-6325 4925);
DISPLAY INVISIBLE (-6325 4925);
FORCEPROP 0 LAST CDS_SEC 1
J 0
(-6325 4925);
DISPLAY 1.021277 (-6325 4925);
DISPLAY INVISIBLE (-6325 4925);
FORCEPROP 1 LASTPIN (-6550 4875) $PN 1
J 0
(-6538 4887);
DISPLAY 0.489362 (-6538 4887);
PAINT MONO (-6538 4887);
FORCEPROP 1 LASTPIN (-6350 4875) $PN 2
J 0
(-6388 4887);
DISPLAY 0.489362 (-6388 4887);
PAINT MONO (-6388 4887);
FORCEPROP 1 LAST VALUE 0
J 2
(-6575 4875);
DISPLAY 0.489362 (-6575 4875);
PAINT SKYBLUE (-6575 4875);
FORCEPROP 2 LAST BOM_COST MEM
J 2
(-6425 5025);
DISPLAY 0.744681 (-6425 5025);
PAINT WHITE (-6425 5025);
DISPLAY INVISIBLE (-6425 5025);
FORCEPROP 2 LAST CDS_LIB pure_quanta
J 2
(-6450 4875);
DISPLAY INVISIBLE (-6450 4875);
FORCEPROP 1 LAST WATTAGE 1/16W
J 2
(-6525 4800);
DISPLAY 0.489362 (-6525 4800);
PAINT SKYBLUE (-6525 4800);
DISPLAY INVISIBLE (-6525 4800);
FORCEPROP 1 LAST MATERIAL CHIP
J 2
(-6275 4850);
DISPLAY 0.489362 (-6275 4850);
PAINT SKYBLUE (-6275 4850);
DISPLAY INVISIBLE (-6275 4850);
FORCEPROP 1 LAST TOLERANCE 5%
J 0
(-6575 4850);
DISPLAY 0.489362 (-6575 4850);
PAINT SKYBLUE (-6575 4850);
DISPLAY INVISIBLE (-6575 4850);
FORCEPROP 1 LAST PACK_TYPE 0402LF
J 2
(-6275 4800);
DISPLAY 0.489362 (-6275 4800);
PAINT SKYBLUE (-6275 4800);
DISPLAY INVISIBLE (-6275 4800);
FORCEPROP 1 LAST PATH I54
J 0
(-6500 5025);
DISPLAY 0.978723 (-6500 5025);
PAINT WHITE (-6500 5025);
DISPLAY INVISIBLE (-6500 5025);
FORCEPROP 1 LAST PART_NUMBER CS00002JB13
J 2
(-6350 4925);
DISPLAY 0.489362 (-6350 4925);
PAINT SKYBLUE (-6350 4925);
DISPLAY INVISIBLE (-6350 4925);
FORCEADD Q_RES..1
(-6450 4925);
FORCEPROP 1 LAST LOCATION R268
J 0
(-6325 4925);
DISPLAY 0.489362 (-6325 4925);
PAINT SKYBLUE (-6325 4925);
FORCEPROP 0 LAST $SEC 1
J 0
(-6325 4975);
DISPLAY 0.680851 (-6325 4975);
PAINT MONO (-6325 4975);
DISPLAY INVISIBLE (-6325 4975);
FORCEPROP 0 LAST CDS_SEC 1
J 0
(-6325 4975);
DISPLAY 1.021277 (-6325 4975);
DISPLAY INVISIBLE (-6325 4975);
FORCEPROP 1 LASTPIN (-6550 4925) $PN 1
J 0
(-6538 4937);
DISPLAY 0.489362 (-6538 4937);
PAINT MONO (-6538 4937);
FORCEPROP 1 LASTPIN (-6350 4925) $PN 2
J 0
(-6388 4937);
DISPLAY 0.489362 (-6388 4937);
PAINT MONO (-6388 4937);
FORCEPROP 1 LAST VALUE 0
J 2
(-6575 4925);
DISPLAY 0.489362 (-6575 4925);
PAINT SKYBLUE (-6575 4925);
FORCEPROP 2 LAST BOM_COST MEM
J 2
(-6425 5075);
DISPLAY 0.744681 (-6425 5075);
PAINT WHITE (-6425 5075);
DISPLAY INVISIBLE (-6425 5075);
FORCEPROP 2 LAST CDS_LIB pure_quanta
J 2
(-6450 4925);
DISPLAY INVISIBLE (-6450 4925);
FORCEPROP 1 LAST WATTAGE 1/16W
J 2
(-6525 4850);
DISPLAY 0.489362 (-6525 4850);
PAINT SKYBLUE (-6525 4850);
DISPLAY INVISIBLE (-6525 4850);
FORCEPROP 1 LAST MATERIAL CHIP
J 2
(-6275 4900);
DISPLAY 0.489362 (-6275 4900);
PAINT SKYBLUE (-6275 4900);
DISPLAY INVISIBLE (-6275 4900);
FORCEPROP 1 LAST TOLERANCE 5%
J 0
(-6575 4900);
DISPLAY 0.489362 (-6575 4900);
PAINT SKYBLUE (-6575 4900);
DISPLAY INVISIBLE (-6575 4900);
FORCEPROP 1 LAST PACK_TYPE 0402LF
J 2
(-6275 4850);
DISPLAY 0.489362 (-6275 4850);
PAINT SKYBLUE (-6275 4850);
DISPLAY INVISIBLE (-6275 4850);
FORCEPROP 1 LAST PATH I55
J 0
(-6500 5075);
DISPLAY 0.978723 (-6500 5075);
PAINT WHITE (-6500 5075);
DISPLAY INVISIBLE (-6500 5075);
FORCEPROP 1 LAST PART_NUMBER CS00002JB13
J 2
(-6350 4975);
DISPLAY 0.489362 (-6350 4975);
PAINT SKYBLUE (-6350 4975);
DISPLAY INVISIBLE (-6350 4975);
FORCEADD Q_RES..1
(-6450 4975);
FORCEPROP 1 LAST LOCATION R269
J 0
(-6325 4975);
DISPLAY 0.489362 (-6325 4975);
PAINT SKYBLUE (-6325 4975);
FORCEPROP 0 LAST $SEC 1
J 0
(-6325 5025);
DISPLAY 0.680851 (-6325 5025);
PAINT MONO (-6325 5025);
DISPLAY INVISIBLE (-6325 5025);
FORCEPROP 0 LAST CDS_SEC 1
J 0
(-6325 5025);
DISPLAY 1.021277 (-6325 5025);
DISPLAY INVISIBLE (-6325 5025);
FORCEPROP 1 LASTPIN (-6550 4975) $PN 1
J 0
(-6538 4987);
DISPLAY 0.489362 (-6538 4987);
PAINT MONO (-6538 4987);
FORCEPROP 1 LASTPIN (-6350 4975) $PN 2
J 0
(-6388 4987);
DISPLAY 0.489362 (-6388 4987);
PAINT MONO (-6388 4987);
FORCEPROP 1 LAST VALUE 0
J 2
(-6575 4975);
DISPLAY 0.489362 (-6575 4975);
PAINT SKYBLUE (-6575 4975);
FORCEPROP 2 LAST CDS_LIB pure_quanta
J 2
(-6450 4975);
DISPLAY INVISIBLE (-6450 4975);
FORCEPROP 2 LAST BOM_COST MEM
J 2
(-6425 5125);
DISPLAY 0.744681 (-6425 5125);
PAINT WHITE (-6425 5125);
DISPLAY INVISIBLE (-6425 5125);
FORCEPROP 1 LAST WATTAGE 1/16W
J 2
(-6525 4900);
DISPLAY 0.489362 (-6525 4900);
PAINT SKYBLUE (-6525 4900);
DISPLAY INVISIBLE (-6525 4900);
FORCEPROP 1 LAST MATERIAL CHIP
J 2
(-6275 4950);
DISPLAY 0.489362 (-6275 4950);
PAINT SKYBLUE (-6275 4950);
DISPLAY INVISIBLE (-6275 4950);
FORCEPROP 1 LAST TOLERANCE 5%
J 0
(-6575 4950);
DISPLAY 0.489362 (-6575 4950);
PAINT SKYBLUE (-6575 4950);
DISPLAY INVISIBLE (-6575 4950);
FORCEPROP 1 LAST PACK_TYPE 0402LF
J 2
(-6275 4900);
DISPLAY 0.489362 (-6275 4900);
PAINT SKYBLUE (-6275 4900);
DISPLAY INVISIBLE (-6275 4900);
FORCEPROP 1 LAST PATH I56
J 0
(-6500 5125);
DISPLAY 0.978723 (-6500 5125);
PAINT WHITE (-6500 5125);
DISPLAY INVISIBLE (-6500 5125);
FORCEPROP 1 LAST PART_NUMBER CS00002JB13
J 2
(-6350 5025);
DISPLAY 0.489362 (-6350 5025);
PAINT SKYBLUE (-6350 5025);
DISPLAY INVISIBLE (-6350 5025);
FORCEADD Q_RES..1
(-6450 5175);
FORCEPROP 1 LAST LOCATION R141
J 0
(-6325 5175);
DISPLAY 0.489362 (-6325 5175);
PAINT SKYBLUE (-6325 5175);
FORCEPROP 0 LAST $SEC 1
J 0
(-6325 5225);
DISPLAY 0.680851 (-6325 5225);
PAINT MONO (-6325 5225);
DISPLAY INVISIBLE (-6325 5225);
FORCEPROP 0 LAST CDS_SEC 1
J 0
(-6325 5225);
DISPLAY 1.021277 (-6325 5225);
DISPLAY INVISIBLE (-6325 5225);
FORCEPROP 1 LASTPIN (-6550 5175) $PN 1
J 0
(-6538 5187);
DISPLAY 0.489362 (-6538 5187);
PAINT MONO (-6538 5187);
FORCEPROP 1 LASTPIN (-6350 5175) $PN 2
J 0
(-6388 5187);
DISPLAY 0.489362 (-6388 5187);
PAINT MONO (-6388 5187);
FORCEPROP 1 LAST VALUE 0
J 2
(-6575 5175);
DISPLAY 0.489362 (-6575 5175);
PAINT SKYBLUE (-6575 5175);
FORCEPROP 1 LAST PACK_TYPE 0402LF
J 2
(-6275 5100);
DISPLAY 0.489362 (-6275 5100);
PAINT SKYBLUE (-6275 5100);
DISPLAY INVISIBLE (-6275 5100);
FORCEPROP 1 LAST TOLERANCE 5%
J 0
(-6575 5150);
DISPLAY 0.489362 (-6575 5150);
PAINT SKYBLUE (-6575 5150);
DISPLAY INVISIBLE (-6575 5150);
FORCEPROP 1 LAST MATERIAL CHIP
J 2
(-6275 5150);
DISPLAY 0.489362 (-6275 5150);
PAINT SKYBLUE (-6275 5150);
DISPLAY INVISIBLE (-6275 5150);
FORCEPROP 1 LAST WATTAGE 1/16W
J 2
(-6525 5100);
DISPLAY 0.489362 (-6525 5100);
PAINT SKYBLUE (-6525 5100);
DISPLAY INVISIBLE (-6525 5100);
FORCEPROP 2 LAST BOM_COST MEM
J 2
(-6425 5325);
DISPLAY 0.744681 (-6425 5325);
PAINT WHITE (-6425 5325);
DISPLAY INVISIBLE (-6425 5325);
FORCEPROP 2 LAST CDS_LIB pure_quanta
J 2
(-6450 5175);
DISPLAY INVISIBLE (-6450 5175);
FORCEPROP 1 LAST PATH I57
J 0
(-6500 5325);
DISPLAY 0.978723 (-6500 5325);
PAINT WHITE (-6500 5325);
DISPLAY INVISIBLE (-6500 5325);
FORCEPROP 1 LAST PART_NUMBER CS00002JB13
J 2
(-6350 5225);
DISPLAY 0.489362 (-6350 5225);
PAINT SKYBLUE (-6350 5225);
DISPLAY INVISIBLE (-6350 5225);
FORCEADD Q_RES..1
(-6450 5325);
FORCEPROP 1 LAST LOCATION R189
J 0
(-6325 5325);
DISPLAY 0.489362 (-6325 5325);
PAINT SKYBLUE (-6325 5325);
FORCEPROP 0 LAST $SEC 1
J 2
(-6325 5375);
DISPLAY 0.680851 (-6325 5375);
PAINT MONO (-6325 5375);
DISPLAY INVISIBLE (-6325 5375);
FORCEPROP 0 LAST CDS_SEC 1
J 2
(-6325 5375);
DISPLAY 1.021277 (-6325 5375);
DISPLAY INVISIBLE (-6325 5375);
FORCEPROP 1 LASTPIN (-6550 5325) $PN 1
J 0
(-6538 5337);
DISPLAY 0.489362 (-6538 5337);
PAINT MONO (-6538 5337);
FORCEPROP 1 LASTPIN (-6350 5325) $PN 2
J 0
(-6388 5337);
DISPLAY 0.489362 (-6388 5337);
PAINT MONO (-6388 5337);
FORCEPROP 1 LAST VALUE 0
J 2
(-6575 5325);
DISPLAY 0.489362 (-6575 5325);
PAINT SKYBLUE (-6575 5325);
FORCEPROP 2 LAST CDS_LIB pure_quanta
J 2
(-6450 5325);
DISPLAY INVISIBLE (-6450 5325);
FORCEPROP 2 LAST BOM_COST MEM
J 2
(-6425 5475);
DISPLAY 0.744681 (-6425 5475);
PAINT WHITE (-6425 5475);
DISPLAY INVISIBLE (-6425 5475);
FORCEPROP 1 LAST WATTAGE 1/16W
J 2
(-6525 5250);
DISPLAY 0.489362 (-6525 5250);
PAINT SKYBLUE (-6525 5250);
DISPLAY INVISIBLE (-6525 5250);
FORCEPROP 1 LAST MATERIAL CHIP
J 2
(-6275 5300);
DISPLAY 0.489362 (-6275 5300);
PAINT SKYBLUE (-6275 5300);
DISPLAY INVISIBLE (-6275 5300);
FORCEPROP 1 LAST TOLERANCE 5%
J 0
(-6575 5300);
DISPLAY 0.489362 (-6575 5300);
PAINT SKYBLUE (-6575 5300);
DISPLAY INVISIBLE (-6575 5300);
FORCEPROP 1 LAST PACK_TYPE 0402LF
J 2
(-6275 5250);
DISPLAY 0.489362 (-6275 5250);
PAINT SKYBLUE (-6275 5250);
DISPLAY INVISIBLE (-6275 5250);
FORCEPROP 1 LAST PATH I58
J 0
(-6500 5475);
DISPLAY 0.978723 (-6500 5475);
PAINT WHITE (-6500 5475);
DISPLAY INVISIBLE (-6500 5475);
FORCEPROP 1 LAST PART_NUMBER CS00002JB13
J 2
(-6350 5375);
DISPLAY 0.489362 (-6350 5375);
PAINT SKYBLUE (-6350 5375);
DISPLAY INVISIBLE (-6350 5375);
FORCEADD Q_RES..1
(-6450 5225);
FORCEPROP 1 LAST LOCATION R137
J 0
(-6325 5225);
DISPLAY 0.489362 (-6325 5225);
PAINT SKYBLUE (-6325 5225);
FORCEPROP 0 LAST $SEC 1
J 0
(-6325 5275);
DISPLAY 0.680851 (-6325 5275);
PAINT MONO (-6325 5275);
DISPLAY INVISIBLE (-6325 5275);
FORCEPROP 0 LAST CDS_SEC 1
J 0
(-6325 5275);
DISPLAY 1.021277 (-6325 5275);
DISPLAY INVISIBLE (-6325 5275);
FORCEPROP 1 LASTPIN (-6550 5225) $PN 1
J 0
(-6538 5237);
DISPLAY 0.489362 (-6538 5237);
PAINT MONO (-6538 5237);
FORCEPROP 1 LASTPIN (-6350 5225) $PN 2
J 0
(-6388 5237);
DISPLAY 0.489362 (-6388 5237);
PAINT MONO (-6388 5237);
FORCEPROP 1 LAST VALUE 0
J 2
(-6575 5225);
DISPLAY 0.489362 (-6575 5225);
PAINT SKYBLUE (-6575 5225);
FORCEPROP 2 LAST BOM_COST MEM
J 2
(-6425 5375);
DISPLAY 0.744681 (-6425 5375);
PAINT WHITE (-6425 5375);
DISPLAY INVISIBLE (-6425 5375);
FORCEPROP 2 LAST CDS_LIB pure_quanta
J 2
(-6450 5225);
DISPLAY INVISIBLE (-6450 5225);
FORCEPROP 1 LAST WATTAGE 1/16W
J 2
(-6525 5150);
DISPLAY 0.489362 (-6525 5150);
PAINT SKYBLUE (-6525 5150);
DISPLAY INVISIBLE (-6525 5150);
FORCEPROP 1 LAST MATERIAL CHIP
J 2
(-6275 5200);
DISPLAY 0.489362 (-6275 5200);
PAINT SKYBLUE (-6275 5200);
DISPLAY INVISIBLE (-6275 5200);
FORCEPROP 1 LAST TOLERANCE 5%
J 0
(-6575 5200);
DISPLAY 0.489362 (-6575 5200);
PAINT SKYBLUE (-6575 5200);
DISPLAY INVISIBLE (-6575 5200);
FORCEPROP 1 LAST PACK_TYPE 0402LF
J 2
(-6275 5150);
DISPLAY 0.489362 (-6275 5150);
PAINT SKYBLUE (-6275 5150);
DISPLAY INVISIBLE (-6275 5150);
FORCEPROP 1 LAST PATH I59
J 0
(-6500 5375);
DISPLAY 0.978723 (-6500 5375);
PAINT WHITE (-6500 5375);
DISPLAY INVISIBLE (-6500 5375);
FORCEPROP 1 LAST PART_NUMBER CS00002JB13
J 2
(-6350 5275);
DISPLAY 0.489362 (-6350 5275);
PAINT SKYBLUE (-6350 5275);
DISPLAY INVISIBLE (-6350 5275);
FORCEADD Q_RES..1
(-6450 5275);
FORCEPROP 1 LAST LOCATION R231
J 0
(-6325 5275);
DISPLAY 0.489362 (-6325 5275);
PAINT SKYBLUE (-6325 5275);
FORCEPROP 0 LAST $SEC 1
J 0
(-6325 5325);
DISPLAY 0.680851 (-6325 5325);
PAINT MONO (-6325 5325);
DISPLAY INVISIBLE (-6325 5325);
FORCEPROP 0 LAST CDS_SEC 1
J 0
(-6325 5325);
DISPLAY 1.021277 (-6325 5325);
DISPLAY INVISIBLE (-6325 5325);
FORCEPROP 1 LASTPIN (-6550 5275) $PN 1
J 0
(-6538 5287);
DISPLAY 0.489362 (-6538 5287);
PAINT MONO (-6538 5287);
FORCEPROP 1 LASTPIN (-6350 5275) $PN 2
J 0
(-6388 5287);
DISPLAY 0.489362 (-6388 5287);
PAINT MONO (-6388 5287);
FORCEPROP 1 LAST VALUE 0
J 2
(-6575 5275);
DISPLAY 0.489362 (-6575 5275);
PAINT SKYBLUE (-6575 5275);
FORCEPROP 2 LAST CDS_LIB pure_quanta
J 2
(-6450 5275);
DISPLAY INVISIBLE (-6450 5275);
FORCEPROP 2 LAST BOM_COST MEM
J 2
(-6425 5425);
DISPLAY 0.744681 (-6425 5425);
PAINT WHITE (-6425 5425);
DISPLAY INVISIBLE (-6425 5425);
FORCEPROP 1 LAST WATTAGE 1/16W
J 2
(-6525 5200);
DISPLAY 0.489362 (-6525 5200);
PAINT SKYBLUE (-6525 5200);
DISPLAY INVISIBLE (-6525 5200);
FORCEPROP 1 LAST MATERIAL CHIP
J 2
(-6275 5250);
DISPLAY 0.489362 (-6275 5250);
PAINT SKYBLUE (-6275 5250);
DISPLAY INVISIBLE (-6275 5250);
FORCEPROP 1 LAST TOLERANCE 5%
J 0
(-6575 5250);
DISPLAY 0.489362 (-6575 5250);
PAINT SKYBLUE (-6575 5250);
DISPLAY INVISIBLE (-6575 5250);
FORCEPROP 1 LAST PACK_TYPE 0402LF
J 2
(-6275 5200);
DISPLAY 0.489362 (-6275 5200);
PAINT SKYBLUE (-6275 5200);
DISPLAY INVISIBLE (-6275 5200);
FORCEPROP 1 LAST PATH I60
J 0
(-6500 5425);
DISPLAY 0.978723 (-6500 5425);
PAINT WHITE (-6500 5425);
DISPLAY INVISIBLE (-6500 5425);
FORCEPROP 1 LAST PART_NUMBER CS00002JB13
J 2
(-6350 5325);
DISPLAY 0.489362 (-6350 5325);
PAINT SKYBLUE (-6350 5325);
DISPLAY INVISIBLE (-6350 5325);
FORCEADD Q_RES..1
(-6450 5375);
FORCEPROP 1 LAST LOCATION R188
J 0
(-6325 5375);
DISPLAY 0.489362 (-6325 5375);
PAINT SKYBLUE (-6325 5375);
FORCEPROP 0 LAST $SEC 1
J 2
(-6325 5425);
DISPLAY 0.680851 (-6325 5425);
PAINT MONO (-6325 5425);
DISPLAY INVISIBLE (-6325 5425);
FORCEPROP 0 LAST CDS_SEC 1
J 2
(-6325 5425);
DISPLAY 1.021277 (-6325 5425);
DISPLAY INVISIBLE (-6325 5425);
FORCEPROP 1 LASTPIN (-6550 5375) $PN 1
J 0
(-6538 5387);
DISPLAY 0.489362 (-6538 5387);
PAINT MONO (-6538 5387);
FORCEPROP 1 LASTPIN (-6350 5375) $PN 2
J 0
(-6388 5387);
DISPLAY 0.489362 (-6388 5387);
PAINT MONO (-6388 5387);
FORCEPROP 1 LAST VALUE 0
J 2
(-6575 5375);
DISPLAY 0.489362 (-6575 5375);
PAINT SKYBLUE (-6575 5375);
FORCEPROP 2 LAST CDS_LIB pure_quanta
J 2
(-6450 5375);
DISPLAY INVISIBLE (-6450 5375);
FORCEPROP 2 LAST BOM_COST MEM
J 2
(-6425 5525);
DISPLAY 0.744681 (-6425 5525);
PAINT WHITE (-6425 5525);
DISPLAY INVISIBLE (-6425 5525);
FORCEPROP 1 LAST WATTAGE 1/16W
J 2
(-6525 5300);
DISPLAY 0.489362 (-6525 5300);
PAINT SKYBLUE (-6525 5300);
DISPLAY INVISIBLE (-6525 5300);
FORCEPROP 1 LAST MATERIAL CHIP
J 2
(-6275 5350);
DISPLAY 0.489362 (-6275 5350);
PAINT SKYBLUE (-6275 5350);
DISPLAY INVISIBLE (-6275 5350);
FORCEPROP 1 LAST TOLERANCE 5%
J 0
(-6575 5350);
DISPLAY 0.489362 (-6575 5350);
PAINT SKYBLUE (-6575 5350);
DISPLAY INVISIBLE (-6575 5350);
FORCEPROP 1 LAST PACK_TYPE 0402LF
J 2
(-6275 5300);
DISPLAY 0.489362 (-6275 5300);
PAINT SKYBLUE (-6275 5300);
DISPLAY INVISIBLE (-6275 5300);
FORCEPROP 1 LAST PATH I61
J 0
(-6500 5525);
DISPLAY 0.978723 (-6500 5525);
PAINT WHITE (-6500 5525);
DISPLAY INVISIBLE (-6500 5525);
FORCEPROP 1 LAST PART_NUMBER CS00002JB13
J 2
(-6350 5425);
DISPLAY 0.489362 (-6350 5425);
PAINT SKYBLUE (-6350 5425);
DISPLAY INVISIBLE (-6350 5425);
FORCEADD Q_RES..1
(-6450 5425);
FORCEPROP 1 LAST LOCATION R239
J 0
(-6325 5425);
DISPLAY 0.489362 (-6325 5425);
PAINT SKYBLUE (-6325 5425);
FORCEPROP 0 LAST $SEC 1
J 2
(-6325 5475);
DISPLAY 0.680851 (-6325 5475);
PAINT MONO (-6325 5475);
DISPLAY INVISIBLE (-6325 5475);
FORCEPROP 0 LAST CDS_SEC 1
J 2
(-6325 5475);
DISPLAY 1.021277 (-6325 5475);
DISPLAY INVISIBLE (-6325 5475);
FORCEPROP 1 LASTPIN (-6550 5425) $PN 1
J 0
(-6538 5437);
DISPLAY 0.489362 (-6538 5437);
PAINT MONO (-6538 5437);
FORCEPROP 1 LASTPIN (-6350 5425) $PN 2
J 0
(-6388 5437);
DISPLAY 0.489362 (-6388 5437);
PAINT MONO (-6388 5437);
FORCEPROP 1 LAST VALUE 0
J 2
(-6575 5425);
DISPLAY 0.489362 (-6575 5425);
PAINT SKYBLUE (-6575 5425);
FORCEPROP 2 LAST CDS_LIB pure_quanta
J 2
(-6450 5425);
DISPLAY INVISIBLE (-6450 5425);
FORCEPROP 2 LAST BOM_COST MEM
J 2
(-6425 5575);
DISPLAY 0.744681 (-6425 5575);
PAINT WHITE (-6425 5575);
DISPLAY INVISIBLE (-6425 5575);
FORCEPROP 1 LAST WATTAGE 1/16W
J 2
(-6525 5350);
DISPLAY 0.489362 (-6525 5350);
PAINT SKYBLUE (-6525 5350);
DISPLAY INVISIBLE (-6525 5350);
FORCEPROP 1 LAST MATERIAL CHIP
J 2
(-6275 5400);
DISPLAY 0.489362 (-6275 5400);
PAINT SKYBLUE (-6275 5400);
DISPLAY INVISIBLE (-6275 5400);
FORCEPROP 1 LAST TOLERANCE 5%
J 0
(-6575 5400);
DISPLAY 0.489362 (-6575 5400);
PAINT SKYBLUE (-6575 5400);
DISPLAY INVISIBLE (-6575 5400);
FORCEPROP 1 LAST PACK_TYPE 0402LF
J 2
(-6275 5350);
DISPLAY 0.489362 (-6275 5350);
PAINT SKYBLUE (-6275 5350);
DISPLAY INVISIBLE (-6275 5350);
FORCEPROP 1 LAST PATH I62
J 0
(-6500 5575);
DISPLAY 0.978723 (-6500 5575);
PAINT WHITE (-6500 5575);
DISPLAY INVISIBLE (-6500 5575);
FORCEPROP 1 LAST PART_NUMBER CS00002JB13
J 2
(-6350 5475);
DISPLAY 0.489362 (-6350 5475);
PAINT SKYBLUE (-6350 5475);
DISPLAY INVISIBLE (-6350 5475);
FORCEADD Q_RES..1
(-6450 5525);
FORCEPROP 1 LAST LOCATION R243
J 0
(-6325 5525);
DISPLAY 0.489362 (-6325 5525);
PAINT SKYBLUE (-6325 5525);
FORCEPROP 0 LAST $SEC 1
J 2
(-6325 5575);
DISPLAY 0.680851 (-6325 5575);
PAINT MONO (-6325 5575);
DISPLAY INVISIBLE (-6325 5575);
FORCEPROP 0 LAST CDS_SEC 1
J 2
(-6325 5575);
DISPLAY 1.021277 (-6325 5575);
DISPLAY INVISIBLE (-6325 5575);
FORCEPROP 1 LASTPIN (-6550 5525) $PN 1
J 0
(-6538 5537);
DISPLAY 0.489362 (-6538 5537);
PAINT MONO (-6538 5537);
FORCEPROP 1 LASTPIN (-6350 5525) $PN 2
J 0
(-6388 5537);
DISPLAY 0.489362 (-6388 5537);
PAINT MONO (-6388 5537);
FORCEPROP 1 LAST VALUE 0
J 2
(-6575 5525);
DISPLAY 0.489362 (-6575 5525);
PAINT SKYBLUE (-6575 5525);
FORCEPROP 2 LAST BOM_COST MEM
J 2
(-6425 5675);
DISPLAY 0.744681 (-6425 5675);
PAINT WHITE (-6425 5675);
DISPLAY INVISIBLE (-6425 5675);
FORCEPROP 2 LAST CDS_LIB pure_quanta
J 2
(-6450 5525);
DISPLAY INVISIBLE (-6450 5525);
FORCEPROP 1 LAST WATTAGE 1/16W
J 2
(-6525 5450);
DISPLAY 0.489362 (-6525 5450);
PAINT SKYBLUE (-6525 5450);
DISPLAY INVISIBLE (-6525 5450);
FORCEPROP 1 LAST MATERIAL CHIP
J 2
(-6275 5500);
DISPLAY 0.489362 (-6275 5500);
PAINT SKYBLUE (-6275 5500);
DISPLAY INVISIBLE (-6275 5500);
FORCEPROP 1 LAST TOLERANCE 5%
J 0
(-6575 5500);
DISPLAY 0.489362 (-6575 5500);
PAINT SKYBLUE (-6575 5500);
DISPLAY INVISIBLE (-6575 5500);
FORCEPROP 1 LAST PACK_TYPE 0402LF
J 2
(-6275 5450);
DISPLAY 0.489362 (-6275 5450);
PAINT SKYBLUE (-6275 5450);
DISPLAY INVISIBLE (-6275 5450);
FORCEPROP 1 LAST PATH I63
J 0
(-6500 5675);
DISPLAY 0.978723 (-6500 5675);
PAINT WHITE (-6500 5675);
DISPLAY INVISIBLE (-6500 5675);
FORCEPROP 1 LAST PART_NUMBER CS00002JB13
J 2
(-6350 5575);
DISPLAY 0.489362 (-6350 5575);
PAINT SKYBLUE (-6350 5575);
DISPLAY INVISIBLE (-6350 5575);
FORCEADD Q_RES..1
(-6450 5475);
FORCEPROP 1 LAST LOCATION R190
J 0
(-6325 5475);
DISPLAY 0.489362 (-6325 5475);
PAINT SKYBLUE (-6325 5475);
FORCEPROP 0 LAST $SEC 1
J 2
(-6325 5525);
DISPLAY 0.680851 (-6325 5525);
PAINT MONO (-6325 5525);
DISPLAY INVISIBLE (-6325 5525);
FORCEPROP 0 LAST CDS_SEC 1
J 2
(-6325 5525);
DISPLAY 1.021277 (-6325 5525);
DISPLAY INVISIBLE (-6325 5525);
FORCEPROP 1 LASTPIN (-6550 5475) $PN 1
J 0
(-6538 5487);
DISPLAY 0.489362 (-6538 5487);
PAINT MONO (-6538 5487);
FORCEPROP 1 LASTPIN (-6350 5475) $PN 2
J 0
(-6388 5487);
DISPLAY 0.489362 (-6388 5487);
PAINT MONO (-6388 5487);
FORCEPROP 1 LAST VALUE 0
J 2
(-6575 5475);
DISPLAY 0.489362 (-6575 5475);
PAINT SKYBLUE (-6575 5475);
FORCEPROP 2 LAST CDS_LIB pure_quanta
J 2
(-6450 5475);
DISPLAY INVISIBLE (-6450 5475);
FORCEPROP 2 LAST BOM_COST MEM
J 2
(-6425 5625);
DISPLAY 0.744681 (-6425 5625);
PAINT WHITE (-6425 5625);
DISPLAY INVISIBLE (-6425 5625);
FORCEPROP 1 LAST WATTAGE 1/16W
J 2
(-6525 5400);
DISPLAY 0.489362 (-6525 5400);
PAINT SKYBLUE (-6525 5400);
DISPLAY INVISIBLE (-6525 5400);
FORCEPROP 1 LAST MATERIAL CHIP
J 2
(-6275 5450);
DISPLAY 0.489362 (-6275 5450);
PAINT SKYBLUE (-6275 5450);
DISPLAY INVISIBLE (-6275 5450);
FORCEPROP 1 LAST TOLERANCE 5%
J 0
(-6575 5450);
DISPLAY 0.489362 (-6575 5450);
PAINT SKYBLUE (-6575 5450);
DISPLAY INVISIBLE (-6575 5450);
FORCEPROP 1 LAST PACK_TYPE 0402LF
J 2
(-6275 5400);
DISPLAY 0.489362 (-6275 5400);
PAINT SKYBLUE (-6275 5400);
DISPLAY INVISIBLE (-6275 5400);
FORCEPROP 1 LAST PATH I64
J 0
(-6500 5625);
DISPLAY 0.978723 (-6500 5625);
PAINT WHITE (-6500 5625);
DISPLAY INVISIBLE (-6500 5625);
FORCEPROP 1 LAST PART_NUMBER CS00002JB13
J 2
(-6350 5525);
DISPLAY 0.489362 (-6350 5525);
PAINT SKYBLUE (-6350 5525);
DISPLAY INVISIBLE (-6350 5525);
FORCEADD Q_RES..1
(-6450 5575);
FORCEPROP 1 LAST LOCATION R246
J 0
(-6325 5575);
DISPLAY 0.489362 (-6325 5575);
PAINT SKYBLUE (-6325 5575);
FORCEPROP 0 LAST $SEC 1
J 2
(-6325 5625);
DISPLAY 0.680851 (-6325 5625);
PAINT MONO (-6325 5625);
DISPLAY INVISIBLE (-6325 5625);
FORCEPROP 0 LAST CDS_SEC 1
J 2
(-6325 5625);
DISPLAY 1.021277 (-6325 5625);
DISPLAY INVISIBLE (-6325 5625);
FORCEPROP 1 LASTPIN (-6550 5575) $PN 1
J 0
(-6538 5587);
DISPLAY 0.489362 (-6538 5587);
PAINT MONO (-6538 5587);
FORCEPROP 1 LASTPIN (-6350 5575) $PN 2
J 0
(-6388 5587);
DISPLAY 0.489362 (-6388 5587);
PAINT MONO (-6388 5587);
FORCEPROP 1 LAST VALUE 0
J 2
(-6575 5575);
DISPLAY 0.489362 (-6575 5575);
PAINT SKYBLUE (-6575 5575);
FORCEPROP 2 LAST BOM_COST MEM
J 2
(-6425 5725);
DISPLAY 0.744681 (-6425 5725);
PAINT WHITE (-6425 5725);
DISPLAY INVISIBLE (-6425 5725);
FORCEPROP 2 LAST CDS_LIB pure_quanta
J 2
(-6450 5575);
DISPLAY INVISIBLE (-6450 5575);
FORCEPROP 1 LAST WATTAGE 1/16W
J 2
(-6525 5500);
DISPLAY 0.489362 (-6525 5500);
PAINT SKYBLUE (-6525 5500);
DISPLAY INVISIBLE (-6525 5500);
FORCEPROP 1 LAST MATERIAL CHIP
J 2
(-6275 5550);
DISPLAY 0.489362 (-6275 5550);
PAINT SKYBLUE (-6275 5550);
DISPLAY INVISIBLE (-6275 5550);
FORCEPROP 1 LAST TOLERANCE 5%
J 0
(-6575 5550);
DISPLAY 0.489362 (-6575 5550);
PAINT SKYBLUE (-6575 5550);
DISPLAY INVISIBLE (-6575 5550);
FORCEPROP 1 LAST PACK_TYPE 0402LF
J 2
(-6275 5500);
DISPLAY 0.489362 (-6275 5500);
PAINT SKYBLUE (-6275 5500);
DISPLAY INVISIBLE (-6275 5500);
FORCEPROP 1 LAST PATH I65
J 0
(-6500 5725);
DISPLAY 0.978723 (-6500 5725);
PAINT WHITE (-6500 5725);
DISPLAY INVISIBLE (-6500 5725);
FORCEPROP 1 LAST PART_NUMBER CS00002JB13
J 2
(-6350 5625);
DISPLAY 0.489362 (-6350 5625);
PAINT SKYBLUE (-6350 5625);
DISPLAY INVISIBLE (-6350 5625);
FORCEADD Q_RES..1
(-6450 5675);
FORCEPROP 1 LAST LOCATION R236
J 0
(-6325 5675);
DISPLAY 0.489362 (-6325 5675);
PAINT SKYBLUE (-6325 5675);
FORCEPROP 0 LAST $SEC 1
J 2
(-6325 5725);
DISPLAY 0.680851 (-6325 5725);
PAINT MONO (-6325 5725);
DISPLAY INVISIBLE (-6325 5725);
FORCEPROP 0 LAST CDS_SEC 1
J 2
(-6325 5725);
DISPLAY 1.021277 (-6325 5725);
DISPLAY INVISIBLE (-6325 5725);
FORCEPROP 1 LASTPIN (-6550 5675) $PN 1
J 0
(-6538 5687);
DISPLAY 0.489362 (-6538 5687);
PAINT MONO (-6538 5687);
FORCEPROP 1 LASTPIN (-6350 5675) $PN 2
J 0
(-6388 5687);
DISPLAY 0.489362 (-6388 5687);
PAINT MONO (-6388 5687);
FORCEPROP 1 LAST VALUE 0
J 2
(-6575 5675);
DISPLAY 0.489362 (-6575 5675);
PAINT SKYBLUE (-6575 5675);
FORCEPROP 2 LAST BOM_COST MEM
J 2
(-6425 5825);
DISPLAY 0.744681 (-6425 5825);
PAINT WHITE (-6425 5825);
DISPLAY INVISIBLE (-6425 5825);
FORCEPROP 2 LAST CDS_LIB pure_quanta
J 2
(-6450 5675);
DISPLAY INVISIBLE (-6450 5675);
FORCEPROP 1 LAST WATTAGE 1/16W
J 2
(-6525 5600);
DISPLAY 0.489362 (-6525 5600);
PAINT SKYBLUE (-6525 5600);
DISPLAY INVISIBLE (-6525 5600);
FORCEPROP 1 LAST MATERIAL CHIP
J 2
(-6275 5650);
DISPLAY 0.489362 (-6275 5650);
PAINT SKYBLUE (-6275 5650);
DISPLAY INVISIBLE (-6275 5650);
FORCEPROP 1 LAST TOLERANCE 5%
J 0
(-6575 5650);
DISPLAY 0.489362 (-6575 5650);
PAINT SKYBLUE (-6575 5650);
DISPLAY INVISIBLE (-6575 5650);
FORCEPROP 1 LAST PACK_TYPE 0402LF
J 2
(-6275 5600);
DISPLAY 0.489362 (-6275 5600);
PAINT SKYBLUE (-6275 5600);
DISPLAY INVISIBLE (-6275 5600);
FORCEPROP 1 LAST PATH I66
J 0
(-6500 5825);
DISPLAY 0.978723 (-6500 5825);
PAINT WHITE (-6500 5825);
DISPLAY INVISIBLE (-6500 5825);
FORCEPROP 1 LAST PART_NUMBER CS00002JB13
J 2
(-6350 5725);
DISPLAY 0.489362 (-6350 5725);
PAINT SKYBLUE (-6350 5725);
DISPLAY INVISIBLE (-6350 5725);
FORCEADD Q_RES..1
(-6450 5625);
FORCEPROP 1 LAST LOCATION R245
J 0
(-6325 5625);
DISPLAY 0.489362 (-6325 5625);
PAINT SKYBLUE (-6325 5625);
FORCEPROP 0 LAST $SEC 1
J 2
(-6325 5675);
DISPLAY 0.680851 (-6325 5675);
PAINT MONO (-6325 5675);
DISPLAY INVISIBLE (-6325 5675);
FORCEPROP 0 LAST CDS_SEC 1
J 2
(-6325 5675);
DISPLAY 1.021277 (-6325 5675);
DISPLAY INVISIBLE (-6325 5675);
FORCEPROP 1 LASTPIN (-6550 5625) $PN 1
J 0
(-6538 5637);
DISPLAY 0.489362 (-6538 5637);
PAINT MONO (-6538 5637);
FORCEPROP 1 LASTPIN (-6350 5625) $PN 2
J 0
(-6388 5637);
DISPLAY 0.489362 (-6388 5637);
PAINT MONO (-6388 5637);
FORCEPROP 1 LAST VALUE 0
J 2
(-6575 5625);
DISPLAY 0.489362 (-6575 5625);
PAINT SKYBLUE (-6575 5625);
FORCEPROP 2 LAST CDS_LIB pure_quanta
J 2
(-6450 5625);
DISPLAY INVISIBLE (-6450 5625);
FORCEPROP 2 LAST BOM_COST MEM
J 2
(-6425 5775);
DISPLAY 0.744681 (-6425 5775);
PAINT WHITE (-6425 5775);
DISPLAY INVISIBLE (-6425 5775);
FORCEPROP 1 LAST WATTAGE 1/16W
J 2
(-6525 5550);
DISPLAY 0.489362 (-6525 5550);
PAINT SKYBLUE (-6525 5550);
DISPLAY INVISIBLE (-6525 5550);
FORCEPROP 1 LAST MATERIAL CHIP
J 2
(-6275 5600);
DISPLAY 0.489362 (-6275 5600);
PAINT SKYBLUE (-6275 5600);
DISPLAY INVISIBLE (-6275 5600);
FORCEPROP 1 LAST TOLERANCE 5%
J 0
(-6575 5600);
DISPLAY 0.489362 (-6575 5600);
PAINT SKYBLUE (-6575 5600);
DISPLAY INVISIBLE (-6575 5600);
FORCEPROP 1 LAST PACK_TYPE 0402LF
J 2
(-6275 5550);
DISPLAY 0.489362 (-6275 5550);
PAINT SKYBLUE (-6275 5550);
DISPLAY INVISIBLE (-6275 5550);
FORCEPROP 1 LAST PATH I67
J 0
(-6500 5775);
DISPLAY 0.978723 (-6500 5775);
PAINT WHITE (-6500 5775);
DISPLAY INVISIBLE (-6500 5775);
FORCEPROP 1 LAST PART_NUMBER CS00002JB13
J 2
(-6350 5675);
DISPLAY 0.489362 (-6350 5675);
PAINT SKYBLUE (-6350 5675);
DISPLAY INVISIBLE (-6350 5675);
FORCEADD Q_RES..1
(-6450 5775);
FORCEPROP 1 LAST LOCATION R187
J 0
(-6325 5775);
DISPLAY 0.489362 (-6325 5775);
PAINT SKYBLUE (-6325 5775);
FORCEPROP 0 LAST $SEC 1
J 2
(-6325 5825);
DISPLAY 0.680851 (-6325 5825);
PAINT MONO (-6325 5825);
DISPLAY INVISIBLE (-6325 5825);
FORCEPROP 0 LAST CDS_SEC 1
J 2
(-6325 5825);
DISPLAY 1.021277 (-6325 5825);
DISPLAY INVISIBLE (-6325 5825);
FORCEPROP 1 LASTPIN (-6550 5775) $PN 1
J 0
(-6538 5787);
DISPLAY 0.489362 (-6538 5787);
PAINT MONO (-6538 5787);
FORCEPROP 1 LASTPIN (-6350 5775) $PN 2
J 0
(-6388 5787);
DISPLAY 0.489362 (-6388 5787);
PAINT MONO (-6388 5787);
FORCEPROP 1 LAST VALUE 0
J 2
(-6575 5775);
DISPLAY 0.489362 (-6575 5775);
PAINT SKYBLUE (-6575 5775);
FORCEPROP 2 LAST BOM_COST MEM
J 2
(-6425 5925);
DISPLAY 0.744681 (-6425 5925);
PAINT WHITE (-6425 5925);
DISPLAY INVISIBLE (-6425 5925);
FORCEPROP 2 LAST CDS_LIB pure_quanta
J 2
(-6450 5775);
DISPLAY INVISIBLE (-6450 5775);
FORCEPROP 1 LAST WATTAGE 1/16W
J 2
(-6525 5700);
DISPLAY 0.489362 (-6525 5700);
PAINT SKYBLUE (-6525 5700);
DISPLAY INVISIBLE (-6525 5700);
FORCEPROP 1 LAST MATERIAL CHIP
J 2
(-6275 5750);
DISPLAY 0.489362 (-6275 5750);
PAINT SKYBLUE (-6275 5750);
DISPLAY INVISIBLE (-6275 5750);
FORCEPROP 1 LAST TOLERANCE 5%
J 0
(-6575 5750);
DISPLAY 0.489362 (-6575 5750);
PAINT SKYBLUE (-6575 5750);
DISPLAY INVISIBLE (-6575 5750);
FORCEPROP 1 LAST PACK_TYPE 0402LF
J 2
(-6275 5700);
DISPLAY 0.489362 (-6275 5700);
PAINT SKYBLUE (-6275 5700);
DISPLAY INVISIBLE (-6275 5700);
FORCEPROP 1 LAST PATH I68
J 0
(-6500 5925);
DISPLAY 0.978723 (-6500 5925);
PAINT WHITE (-6500 5925);
DISPLAY INVISIBLE (-6500 5925);
FORCEPROP 1 LAST PART_NUMBER CS00002JB13
J 2
(-6350 5825);
DISPLAY 0.489362 (-6350 5825);
PAINT SKYBLUE (-6350 5825);
DISPLAY INVISIBLE (-6350 5825);
FORCEADD Q_RES..1
(-6450 5725);
FORCEPROP 1 LAST LOCATION R237
J 0
(-6325 5725);
DISPLAY 0.489362 (-6325 5725);
PAINT SKYBLUE (-6325 5725);
FORCEPROP 0 LAST $SEC 1
J 2
(-6325 5775);
DISPLAY 0.680851 (-6325 5775);
PAINT MONO (-6325 5775);
DISPLAY INVISIBLE (-6325 5775);
FORCEPROP 0 LAST CDS_SEC 1
J 2
(-6325 5775);
DISPLAY 1.021277 (-6325 5775);
DISPLAY INVISIBLE (-6325 5775);
FORCEPROP 1 LASTPIN (-6550 5725) $PN 1
J 0
(-6538 5737);
DISPLAY 0.489362 (-6538 5737);
PAINT MONO (-6538 5737);
FORCEPROP 1 LASTPIN (-6350 5725) $PN 2
J 0
(-6388 5737);
DISPLAY 0.489362 (-6388 5737);
PAINT MONO (-6388 5737);
FORCEPROP 1 LAST VALUE 0
J 2
(-6575 5725);
DISPLAY 0.489362 (-6575 5725);
PAINT SKYBLUE (-6575 5725);
FORCEPROP 2 LAST BOM_COST MEM
J 2
(-6425 5875);
DISPLAY 0.744681 (-6425 5875);
PAINT WHITE (-6425 5875);
DISPLAY INVISIBLE (-6425 5875);
FORCEPROP 2 LAST CDS_LIB pure_quanta
J 2
(-6450 5725);
DISPLAY INVISIBLE (-6450 5725);
FORCEPROP 1 LAST WATTAGE 1/16W
J 2
(-6525 5650);
DISPLAY 0.489362 (-6525 5650);
PAINT SKYBLUE (-6525 5650);
DISPLAY INVISIBLE (-6525 5650);
FORCEPROP 1 LAST MATERIAL CHIP
J 2
(-6275 5700);
DISPLAY 0.489362 (-6275 5700);
PAINT SKYBLUE (-6275 5700);
DISPLAY INVISIBLE (-6275 5700);
FORCEPROP 1 LAST TOLERANCE 5%
J 0
(-6575 5700);
DISPLAY 0.489362 (-6575 5700);
PAINT SKYBLUE (-6575 5700);
DISPLAY INVISIBLE (-6575 5700);
FORCEPROP 1 LAST PACK_TYPE 0402LF
J 2
(-6275 5650);
DISPLAY 0.489362 (-6275 5650);
PAINT SKYBLUE (-6275 5650);
DISPLAY INVISIBLE (-6275 5650);
FORCEPROP 1 LAST PATH I69
J 0
(-6500 5875);
DISPLAY 0.978723 (-6500 5875);
PAINT WHITE (-6500 5875);
DISPLAY INVISIBLE (-6500 5875);
FORCEPROP 1 LAST PART_NUMBER CS00002JB13
J 2
(-6350 5775);
DISPLAY 0.489362 (-6350 5775);
PAINT SKYBLUE (-6350 5775);
DISPLAY INVISIBLE (-6350 5775);
FORCEADD Q_RES..1
(-6450 5825);
FORCEPROP 1 LAST LOCATION R235
J 0
(-6325 5825);
DISPLAY 0.489362 (-6325 5825);
PAINT SKYBLUE (-6325 5825);
FORCEPROP 0 LAST $SEC 1
J 2
(-6325 5875);
DISPLAY 0.680851 (-6325 5875);
PAINT MONO (-6325 5875);
DISPLAY INVISIBLE (-6325 5875);
FORCEPROP 0 LAST CDS_SEC 1
J 2
(-6325 5875);
DISPLAY 1.021277 (-6325 5875);
DISPLAY INVISIBLE (-6325 5875);
FORCEPROP 1 LASTPIN (-6550 5825) $PN 1
J 0
(-6538 5837);
DISPLAY 0.489362 (-6538 5837);
PAINT MONO (-6538 5837);
FORCEPROP 1 LASTPIN (-6350 5825) $PN 2
J 0
(-6388 5837);
DISPLAY 0.489362 (-6388 5837);
PAINT MONO (-6388 5837);
FORCEPROP 1 LAST VALUE 0
J 2
(-6575 5825);
DISPLAY 0.489362 (-6575 5825);
PAINT SKYBLUE (-6575 5825);
FORCEPROP 2 LAST CDS_LIB pure_quanta
J 2
(-6450 5825);
DISPLAY INVISIBLE (-6450 5825);
FORCEPROP 2 LAST BOM_COST MEM
J 2
(-6425 5975);
DISPLAY 0.744681 (-6425 5975);
PAINT WHITE (-6425 5975);
DISPLAY INVISIBLE (-6425 5975);
FORCEPROP 1 LAST WATTAGE 1/16W
J 2
(-6525 5750);
DISPLAY 0.489362 (-6525 5750);
PAINT SKYBLUE (-6525 5750);
DISPLAY INVISIBLE (-6525 5750);
FORCEPROP 1 LAST MATERIAL CHIP
J 2
(-6275 5800);
DISPLAY 0.489362 (-6275 5800);
PAINT SKYBLUE (-6275 5800);
DISPLAY INVISIBLE (-6275 5800);
FORCEPROP 1 LAST TOLERANCE 5%
J 0
(-6575 5800);
DISPLAY 0.489362 (-6575 5800);
PAINT SKYBLUE (-6575 5800);
DISPLAY INVISIBLE (-6575 5800);
FORCEPROP 1 LAST PACK_TYPE 0402LF
J 2
(-6275 5750);
DISPLAY 0.489362 (-6275 5750);
PAINT SKYBLUE (-6275 5750);
DISPLAY INVISIBLE (-6275 5750);
FORCEPROP 1 LAST PATH I70
J 0
(-6500 5975);
DISPLAY 0.978723 (-6500 5975);
PAINT WHITE (-6500 5975);
DISPLAY INVISIBLE (-6500 5975);
FORCEPROP 1 LAST PART_NUMBER CS00002JB13
J 2
(-6350 5875);
DISPLAY 0.489362 (-6350 5875);
PAINT SKYBLUE (-6350 5875);
DISPLAY INVISIBLE (-6350 5875);
FORCEADD Q_RES..1
(-6450 5925);
FORCEPROP 1 LAST LOCATION R238
J 0
(-6325 5925);
DISPLAY 0.489362 (-6325 5925);
PAINT SKYBLUE (-6325 5925);
FORCEPROP 0 LAST $SEC 1
J 2
(-6325 5975);
DISPLAY 0.680851 (-6325 5975);
PAINT MONO (-6325 5975);
DISPLAY INVISIBLE (-6325 5975);
FORCEPROP 0 LAST CDS_SEC 1
J 2
(-6325 5975);
DISPLAY 1.021277 (-6325 5975);
DISPLAY INVISIBLE (-6325 5975);
FORCEPROP 1 LASTPIN (-6550 5925) $PN 1
J 0
(-6538 5937);
DISPLAY 0.489362 (-6538 5937);
PAINT MONO (-6538 5937);
FORCEPROP 1 LASTPIN (-6350 5925) $PN 2
J 0
(-6388 5937);
DISPLAY 0.489362 (-6388 5937);
PAINT MONO (-6388 5937);
FORCEPROP 1 LAST VALUE 0
J 2
(-6575 5925);
DISPLAY 0.489362 (-6575 5925);
PAINT SKYBLUE (-6575 5925);
FORCEPROP 2 LAST BOM_COST MEM
J 2
(-6425 6075);
DISPLAY 0.744681 (-6425 6075);
PAINT WHITE (-6425 6075);
DISPLAY INVISIBLE (-6425 6075);
FORCEPROP 2 LAST CDS_LIB pure_quanta
J 2
(-6450 5925);
DISPLAY INVISIBLE (-6450 5925);
FORCEPROP 1 LAST WATTAGE 1/16W
J 2
(-6525 5850);
DISPLAY 0.489362 (-6525 5850);
PAINT SKYBLUE (-6525 5850);
DISPLAY INVISIBLE (-6525 5850);
FORCEPROP 1 LAST MATERIAL CHIP
J 2
(-6275 5900);
DISPLAY 0.489362 (-6275 5900);
PAINT SKYBLUE (-6275 5900);
DISPLAY INVISIBLE (-6275 5900);
FORCEPROP 1 LAST TOLERANCE 5%
J 0
(-6575 5900);
DISPLAY 0.489362 (-6575 5900);
PAINT SKYBLUE (-6575 5900);
DISPLAY INVISIBLE (-6575 5900);
FORCEPROP 1 LAST PACK_TYPE 0402LF
J 2
(-6275 5850);
DISPLAY 0.489362 (-6275 5850);
PAINT SKYBLUE (-6275 5850);
DISPLAY INVISIBLE (-6275 5850);
FORCEPROP 1 LAST PATH I71
J 0
(-6500 6075);
DISPLAY 0.978723 (-6500 6075);
PAINT WHITE (-6500 6075);
DISPLAY INVISIBLE (-6500 6075);
FORCEPROP 1 LAST PART_NUMBER CS00002JB13
J 2
(-6350 5975);
DISPLAY 0.489362 (-6350 5975);
PAINT SKYBLUE (-6350 5975);
DISPLAY INVISIBLE (-6350 5975);
FORCEADD Q_RES..1
(-6450 5875);
FORCEPROP 1 LAST LOCATION R244
J 0
(-6325 5875);
DISPLAY 0.489362 (-6325 5875);
PAINT SKYBLUE (-6325 5875);
FORCEPROP 0 LAST $SEC 1
J 2
(-6325 5925);
DISPLAY 0.680851 (-6325 5925);
PAINT MONO (-6325 5925);
DISPLAY INVISIBLE (-6325 5925);
FORCEPROP 0 LAST CDS_SEC 1
J 2
(-6325 5925);
DISPLAY 1.021277 (-6325 5925);
DISPLAY INVISIBLE (-6325 5925);
FORCEPROP 1 LASTPIN (-6550 5875) $PN 1
J 0
(-6538 5887);
DISPLAY 0.489362 (-6538 5887);
PAINT MONO (-6538 5887);
FORCEPROP 1 LASTPIN (-6350 5875) $PN 2
J 0
(-6388 5887);
DISPLAY 0.489362 (-6388 5887);
PAINT MONO (-6388 5887);
FORCEPROP 1 LAST VALUE 0
J 2
(-6575 5875);
DISPLAY 0.489362 (-6575 5875);
PAINT SKYBLUE (-6575 5875);
FORCEPROP 2 LAST CDS_LIB pure_quanta
J 2
(-6450 5875);
DISPLAY INVISIBLE (-6450 5875);
FORCEPROP 2 LAST BOM_COST MEM
J 2
(-6425 6025);
DISPLAY 0.744681 (-6425 6025);
PAINT WHITE (-6425 6025);
DISPLAY INVISIBLE (-6425 6025);
FORCEPROP 1 LAST WATTAGE 1/16W
J 2
(-6525 5800);
DISPLAY 0.489362 (-6525 5800);
PAINT SKYBLUE (-6525 5800);
DISPLAY INVISIBLE (-6525 5800);
FORCEPROP 1 LAST MATERIAL CHIP
J 2
(-6275 5850);
DISPLAY 0.489362 (-6275 5850);
PAINT SKYBLUE (-6275 5850);
DISPLAY INVISIBLE (-6275 5850);
FORCEPROP 1 LAST TOLERANCE 5%
J 0
(-6575 5850);
DISPLAY 0.489362 (-6575 5850);
PAINT SKYBLUE (-6575 5850);
DISPLAY INVISIBLE (-6575 5850);
FORCEPROP 1 LAST PACK_TYPE 0402LF
J 2
(-6275 5800);
DISPLAY 0.489362 (-6275 5800);
PAINT SKYBLUE (-6275 5800);
DISPLAY INVISIBLE (-6275 5800);
FORCEPROP 1 LAST PATH I72
J 0
(-6500 6025);
DISPLAY 0.978723 (-6500 6025);
PAINT WHITE (-6500 6025);
DISPLAY INVISIBLE (-6500 6025);
FORCEPROP 1 LAST PART_NUMBER CS00002JB13
J 2
(-6350 5925);
DISPLAY 0.489362 (-6350 5925);
PAINT SKYBLUE (-6350 5925);
DISPLAY INVISIBLE (-6350 5925);
FORCEADD Q_RES..1
(-6450 5975);
FORCEPROP 1 LAST LOCATION R267
J 0
(-6325 5975);
DISPLAY 0.489362 (-6325 5975);
PAINT SKYBLUE (-6325 5975);
FORCEPROP 0 LAST $SEC 1
J 0
(-6325 6000);
DISPLAY 0.680851 (-6325 6000);
PAINT MONO (-6325 6000);
DISPLAY INVISIBLE (-6325 6000);
FORCEPROP 0 LAST CDS_SEC 1
J 0
(-6325 6000);
DISPLAY 0.680851 (-6325 6000);
DISPLAY INVISIBLE (-6325 6000);
FORCEPROP 1 LASTPIN (-6550 5975) $PN 1
J 0
(-6538 5987);
DISPLAY 0.510638 (-6538 5987);
PAINT MONO (-6538 5987);
FORCEPROP 1 LASTPIN (-6350 5975) $PN 2
J 0
(-6388 5987);
DISPLAY 0.510638 (-6388 5987);
PAINT MONO (-6388 5987);
FORCEPROP 1 LAST VALUE 33
J 2
(-6575 5975);
DISPLAY 0.489362 (-6575 5975);
PAINT SKYBLUE (-6575 5975);
FORCEPROP 2 LAST BOM_COST MEM
J 2
(-6425 6125);
DISPLAY 0.744681 (-6425 6125);
PAINT WHITE (-6425 6125);
DISPLAY INVISIBLE (-6425 6125);
FORCEPROP 1 LAST WATTAGE 1/16W
J 2
(-6525 5900);
DISPLAY 0.489362 (-6525 5900);
PAINT SKYBLUE (-6525 5900);
DISPLAY INVISIBLE (-6525 5900);
FORCEPROP 1 LAST MATERIAL CHIP
J 2
(-6275 5950);
DISPLAY 0.489362 (-6275 5950);
PAINT SKYBLUE (-6275 5950);
DISPLAY INVISIBLE (-6275 5950);
FORCEPROP 1 LAST TOLERANCE 5%
J 0
(-6575 5950);
DISPLAY 0.489362 (-6575 5950);
PAINT SKYBLUE (-6575 5950);
DISPLAY INVISIBLE (-6575 5950);
FORCEPROP 1 LAST PACK_TYPE 0402LF
J 2
(-6275 5900);
DISPLAY 0.489362 (-6275 5900);
PAINT SKYBLUE (-6275 5900);
DISPLAY INVISIBLE (-6275 5900);
FORCEPROP 2 LAST CDS_LIB pure_quanta
J 0
(-6450 5975);
DISPLAY INVISIBLE (-6450 5975);
FORCEPROP 1 LAST PATH I73
J 0
(-6500 6125);
DISPLAY 0.978723 (-6500 6125);
PAINT WHITE (-6500 6125);
DISPLAY INVISIBLE (-6500 6125);
FORCEPROP 1 LAST PART_NUMBER CS03302JB10
J 2
(-6350 6025);
DISPLAY 0.489362 (-6350 6025);
PAINT SKYBLUE (-6350 6025);
DISPLAY INVISIBLE (-6350 6025);
FORCEADD Q_RES..1
(-6450 6075);
FORCEPROP 1 LAST LOCATION R205
J 0
(-6325 6075);
DISPLAY 0.489362 (-6325 6075);
PAINT SKYBLUE (-6325 6075);
FORCEPROP 0 LAST $SEC 1
J 2
(-6325 6125);
DISPLAY 0.680851 (-6325 6125);
PAINT MONO (-6325 6125);
DISPLAY INVISIBLE (-6325 6125);
FORCEPROP 0 LAST CDS_SEC 1
J 2
(-6325 6125);
DISPLAY 1.021277 (-6325 6125);
DISPLAY INVISIBLE (-6325 6125);
FORCEPROP 1 LASTPIN (-6550 6075) $PN 1
J 0
(-6538 6087);
DISPLAY 0.489362 (-6538 6087);
PAINT MONO (-6538 6087);
FORCEPROP 1 LASTPIN (-6350 6075) $PN 2
J 0
(-6388 6087);
DISPLAY 0.489362 (-6388 6087);
PAINT MONO (-6388 6087);
FORCEPROP 1 LAST VALUE 0
J 2
(-6575 6075);
DISPLAY 0.489362 (-6575 6075);
PAINT SKYBLUE (-6575 6075);
FORCEPROP 2 LAST CDS_LIB pure_quanta
J 2
(-6450 6075);
DISPLAY INVISIBLE (-6450 6075);
FORCEPROP 2 LAST BOM_COST MEM
J 2
(-6425 6225);
DISPLAY 0.744681 (-6425 6225);
PAINT WHITE (-6425 6225);
DISPLAY INVISIBLE (-6425 6225);
FORCEPROP 1 LAST WATTAGE 1/16W
J 2
(-6525 6000);
DISPLAY 0.489362 (-6525 6000);
PAINT SKYBLUE (-6525 6000);
DISPLAY INVISIBLE (-6525 6000);
FORCEPROP 1 LAST MATERIAL CHIP
J 2
(-6275 6050);
DISPLAY 0.489362 (-6275 6050);
PAINT SKYBLUE (-6275 6050);
DISPLAY INVISIBLE (-6275 6050);
FORCEPROP 1 LAST TOLERANCE 5%
J 0
(-6575 6050);
DISPLAY 0.489362 (-6575 6050);
PAINT SKYBLUE (-6575 6050);
DISPLAY INVISIBLE (-6575 6050);
FORCEPROP 1 LAST PACK_TYPE 0402LF
J 2
(-6275 6000);
DISPLAY 0.489362 (-6275 6000);
PAINT SKYBLUE (-6275 6000);
DISPLAY INVISIBLE (-6275 6000);
FORCEPROP 1 LAST PATH I74
J 0
(-6500 6225);
DISPLAY 0.978723 (-6500 6225);
PAINT WHITE (-6500 6225);
DISPLAY INVISIBLE (-6500 6225);
FORCEPROP 1 LAST PART_NUMBER CS00002JB13
J 2
(-6350 6125);
DISPLAY 0.489362 (-6350 6125);
PAINT SKYBLUE (-6350 6125);
DISPLAY INVISIBLE (-6350 6125);
FORCEADD Q_RES..1
(-6450 6025);
FORCEPROP 1 LAST LOCATION R234
J 0
(-6325 6025);
DISPLAY 0.489362 (-6325 6025);
PAINT SKYBLUE (-6325 6025);
FORCEPROP 0 LAST $SEC 1
J 2
(-6325 6075);
DISPLAY 0.680851 (-6325 6075);
PAINT MONO (-6325 6075);
DISPLAY INVISIBLE (-6325 6075);
FORCEPROP 0 LAST CDS_SEC 1
J 2
(-6325 6075);
DISPLAY 1.021277 (-6325 6075);
DISPLAY INVISIBLE (-6325 6075);
FORCEPROP 1 LASTPIN (-6550 6025) $PN 1
J 0
(-6538 6037);
DISPLAY 0.489362 (-6538 6037);
PAINT MONO (-6538 6037);
FORCEPROP 1 LASTPIN (-6350 6025) $PN 2
J 0
(-6388 6037);
DISPLAY 0.489362 (-6388 6037);
PAINT MONO (-6388 6037);
FORCEPROP 1 LAST VALUE 0
J 2
(-6575 6025);
DISPLAY 0.489362 (-6575 6025);
PAINT SKYBLUE (-6575 6025);
FORCEPROP 2 LAST CDS_LIB pure_quanta
J 2
(-6450 6025);
DISPLAY INVISIBLE (-6450 6025);
FORCEPROP 2 LAST BOM_COST MEM
J 2
(-6425 6175);
DISPLAY 0.744681 (-6425 6175);
PAINT WHITE (-6425 6175);
DISPLAY INVISIBLE (-6425 6175);
FORCEPROP 1 LAST WATTAGE 1/16W
J 2
(-6525 5950);
DISPLAY 0.489362 (-6525 5950);
PAINT SKYBLUE (-6525 5950);
DISPLAY INVISIBLE (-6525 5950);
FORCEPROP 1 LAST MATERIAL CHIP
J 2
(-6275 6000);
DISPLAY 0.489362 (-6275 6000);
PAINT SKYBLUE (-6275 6000);
DISPLAY INVISIBLE (-6275 6000);
FORCEPROP 1 LAST TOLERANCE 5%
J 0
(-6575 6000);
DISPLAY 0.489362 (-6575 6000);
PAINT SKYBLUE (-6575 6000);
DISPLAY INVISIBLE (-6575 6000);
FORCEPROP 1 LAST PACK_TYPE 0402LF
J 2
(-6275 5950);
DISPLAY 0.489362 (-6275 5950);
PAINT SKYBLUE (-6275 5950);
DISPLAY INVISIBLE (-6275 5950);
FORCEPROP 1 LAST PATH I75
J 0
(-6500 6175);
DISPLAY 0.978723 (-6500 6175);
PAINT WHITE (-6500 6175);
DISPLAY INVISIBLE (-6500 6175);
FORCEPROP 1 LAST PART_NUMBER CS00002JB13
J 2
(-6350 6075);
DISPLAY 0.489362 (-6350 6075);
PAINT SKYBLUE (-6350 6075);
DISPLAY INVISIBLE (-6350 6075);
FORCEADD OFFPAGE..6
(-7300 6125);
FORCEPROP 2 LAST $XR1 54 
J 0
(-7639 6125);
DISPLAY 0.638298 (-7639 6125);
PAINT MONO (-7639 6125);
FORCEPROP 2 LAST $XR0 27 
J 0
(-7549 6125);
DISPLAY 0.638298 (-7549 6125);
PAINT MONO (-7549 6125);
FORCEPROP 2 LAST CDS_LIB standard
J 0
(-7300 6125);
DISPLAY INVISIBLE (-7300 6125);
FORCEPROP 1 LAST OFFPAGE TRUE
J 0
(-6975 6000);
DISPLAY 0.872340 (-6975 6000);
PAINT GREEN (-6975 6000);
DISPLAY INVISIBLE (-6975 6000);
FORCEPROP 1 LAST COMMENT_BODY TRUE
J 0
(-7200 6050);
DISPLAY 0.872340 (-7200 6050);
PAINT GREEN (-7200 6050);
DISPLAY INVISIBLE (-7200 6050);
FORCEPROP 2 LAST PATH I76
J 0
(-7575 6175);
DISPLAY 0.680851 (-7575 6175);
DISPLAY INVISIBLE (-7575 6175);
FORCEADD Q_RES..1
(-6450 6125);
FORCEPROP 1 LAST LOCATION R204
J 0
(-6325 6125);
DISPLAY 0.489362 (-6325 6125);
PAINT SKYBLUE (-6325 6125);
FORCEPROP 0 LAST $SEC 1
J 2
(-6325 6175);
DISPLAY 0.680851 (-6325 6175);
PAINT MONO (-6325 6175);
DISPLAY INVISIBLE (-6325 6175);
FORCEPROP 0 LAST CDS_SEC 1
J 2
(-6325 6175);
DISPLAY 1.021277 (-6325 6175);
DISPLAY INVISIBLE (-6325 6175);
FORCEPROP 1 LASTPIN (-6550 6125) $PN 1
J 0
(-6538 6137);
DISPLAY 0.489362 (-6538 6137);
PAINT MONO (-6538 6137);
FORCEPROP 1 LASTPIN (-6350 6125) $PN 2
J 0
(-6388 6137);
DISPLAY 0.489362 (-6388 6137);
PAINT MONO (-6388 6137);
FORCEPROP 1 LAST VALUE 0
J 2
(-6575 6125);
DISPLAY 0.489362 (-6575 6125);
PAINT SKYBLUE (-6575 6125);
FORCEPROP 2 LAST CDS_LIB pure_quanta
J 2
(-6450 6125);
DISPLAY INVISIBLE (-6450 6125);
FORCEPROP 2 LAST BOM_COST MEM
J 2
(-6425 6275);
DISPLAY 0.744681 (-6425 6275);
PAINT WHITE (-6425 6275);
DISPLAY INVISIBLE (-6425 6275);
FORCEPROP 1 LAST WATTAGE 1/16W
J 2
(-6525 6050);
DISPLAY 0.489362 (-6525 6050);
PAINT SKYBLUE (-6525 6050);
DISPLAY INVISIBLE (-6525 6050);
FORCEPROP 1 LAST MATERIAL CHIP
J 2
(-6275 6100);
DISPLAY 0.489362 (-6275 6100);
PAINT SKYBLUE (-6275 6100);
DISPLAY INVISIBLE (-6275 6100);
FORCEPROP 1 LAST TOLERANCE 5%
J 0
(-6575 6100);
DISPLAY 0.489362 (-6575 6100);
PAINT SKYBLUE (-6575 6100);
DISPLAY INVISIBLE (-6575 6100);
FORCEPROP 1 LAST PACK_TYPE 0402LF
J 2
(-6275 6050);
DISPLAY 0.489362 (-6275 6050);
PAINT SKYBLUE (-6275 6050);
DISPLAY INVISIBLE (-6275 6050);
FORCEPROP 1 LAST PATH I77
J 0
(-6500 6275);
DISPLAY 0.978723 (-6500 6275);
PAINT WHITE (-6500 6275);
DISPLAY INVISIBLE (-6500 6275);
FORCEPROP 1 LAST PART_NUMBER CS00002JB13
J 2
(-6350 6175);
DISPLAY 0.489362 (-6350 6175);
PAINT SKYBLUE (-6350 6175);
DISPLAY INVISIBLE (-6350 6175);
FORCEADD UNIVERSAL_POWER..1
R 2
(-3675 1700);
FORCEPROP 3 LASTPIN (-3675 1650) SIG_NAME P3V3_AUX\g
J 0
(-3665 1660);
DISPLAY 0.659574 (-3665 1660);
PAINT MONO (-3665 1660);
DISPLAY INVISIBLE (-3665 1660);
FORCEPROP 1 LAST HDL_POWER P3V3_AUX
J 1
(-3675 1750);
DISPLAY 0.489362 (-3675 1750);
PAINT GREEN (-3675 1750);
FORCEPROP 2 LAST CDS_LIB pure_quanta_power
J 0
(-3675 1700);
DISPLAY INVISIBLE (-3675 1700);
FORCEPROP 1 LAST PATH I78
J 2
(-3725 1725);
DISPLAY 0.872340 (-3725 1725);
PAINT AQUA (-3725 1725);
DISPLAY INVISIBLE (-3725 1725);
FORCEADD VCC_CORE..1
(-3375 1850);
FORCEPROP 3 LASTPIN (-3375 1800) SIG_NAME P1V8_AUX\g
J 0
(-3365 1810);
DISPLAY 0.659574 (-3365 1810);
PAINT MONO (-3365 1810);
DISPLAY INVISIBLE (-3365 1810);
FORCEPROP 1 LAST HDL_POWER P1V8_AUX
J 1
(-3375 1900);
DISPLAY 0.489362 (-3375 1900);
PAINT GREEN (-3375 1900);
FORCEPROP 2 LAST CDS_LIB pure_quanta_power
J 0
(-3375 1850);
DISPLAY INVISIBLE (-3375 1850);
FORCEPROP 1 LAST PATH I79
J 0
(-3325 1875);
DISPLAY 0.872340 (-3325 1875);
PAINT AQUA (-3325 1875);
DISPLAY INVISIBLE (-3325 1875);
FORCEADD Q_RES..1
R 2
(-3250 3525);
FORCEPROP 1 LAST LOCATION R185
J 2
(-3375 3525);
DISPLAY 0.489362 (-3375 3525);
PAINT SKYBLUE (-3375 3525);
FORCEPROP 0 LAST $SEC 1
J 0
(-3375 3575);
DISPLAY 0.680851 (-3375 3575);
PAINT MONO (-3375 3575);
DISPLAY INVISIBLE (-3375 3575);
FORCEPROP 0 LAST CDS_SEC 1
J 0
(-3375 3575);
DISPLAY 1.021277 (-3375 3575);
DISPLAY INVISIBLE (-3375 3575);
FORCEPROP 1 LASTPIN (-3150 3525) $PN 1
J 2
(-3162 3537);
DISPLAY 0.489362 (-3162 3537);
PAINT MONO (-3162 3537);
FORCEPROP 1 LASTPIN (-3350 3525) $PN 2
J 2
(-3312 3537);
DISPLAY 0.489362 (-3312 3537);
PAINT MONO (-3312 3537);
FORCEPROP 1 LAST VALUE 0
J 0
(-3125 3525);
DISPLAY 0.489362 (-3125 3525);
PAINT SKYBLUE (-3125 3525);
FORCEPROP 2 LAST BOM_COST MEM
J 0
(-3275 3675);
DISPLAY 0.744681 (-3275 3675);
PAINT WHITE (-3275 3675);
DISPLAY INVISIBLE (-3275 3675);
FORCEPROP 2 LAST CDS_LIB pure_quanta
J 0
(-3250 3525);
DISPLAY INVISIBLE (-3250 3525);
FORCEPROP 1 LAST WATTAGE 1/16W
J 0
(-3175 3450);
DISPLAY 0.489362 (-3175 3450);
PAINT SKYBLUE (-3175 3450);
DISPLAY INVISIBLE (-3175 3450);
FORCEPROP 1 LAST MATERIAL CHIP
J 0
(-3425 3500);
DISPLAY 0.489362 (-3425 3500);
PAINT SKYBLUE (-3425 3500);
DISPLAY INVISIBLE (-3425 3500);
FORCEPROP 1 LAST TOLERANCE 5%
J 2
(-3125 3500);
DISPLAY 0.489362 (-3125 3500);
PAINT SKYBLUE (-3125 3500);
DISPLAY INVISIBLE (-3125 3500);
FORCEPROP 1 LAST PACK_TYPE 0402LF
J 0
(-3425 3450);
DISPLAY 0.489362 (-3425 3450);
PAINT SKYBLUE (-3425 3450);
DISPLAY INVISIBLE (-3425 3450);
FORCEPROP 1 LAST PATH I80
J 2
(-3200 3675);
DISPLAY 0.978723 (-3200 3675);
PAINT WHITE (-3200 3675);
DISPLAY INVISIBLE (-3200 3675);
FORCEPROP 1 LAST PART_NUMBER CS00002JB13
J 0
(-3350 3575);
DISPLAY 0.489362 (-3350 3575);
PAINT SKYBLUE (-3350 3575);
DISPLAY INVISIBLE (-3350 3575);
FORCEADD Q_RES..1
R 2
(-3250 3475);
FORCEPROP 1 LAST LOCATION R959
J 2
(-3375 3475);
DISPLAY 0.489362 (-3375 3475);
PAINT SKYBLUE (-3375 3475);
FORCEPROP 0 LAST $SEC 1
J 2
(-3375 3500);
DISPLAY 0.680851 (-3375 3500);
PAINT MONO (-3375 3500);
DISPLAY INVISIBLE (-3375 3500);
FORCEPROP 0 LAST CDS_SEC 1
J 2
(-3375 3500);
DISPLAY 0.680851 (-3375 3500);
DISPLAY INVISIBLE (-3375 3500);
FORCEPROP 1 LASTPIN (-3150 3475) $PN 1
J 2
(-3162 3487);
DISPLAY 0.489362 (-3162 3487);
PAINT MONO (-3162 3487);
FORCEPROP 1 LASTPIN (-3350 3475) $PN 2
J 2
(-3312 3487);
DISPLAY 0.489362 (-3312 3487);
PAINT MONO (-3312 3487);
FORCEPROP 1 LAST VALUE 33
J 0
(-3125 3475);
DISPLAY 0.489362 (-3125 3475);
PAINT SKYBLUE (-3125 3475);
FORCEPROP 2 LAST BOM_COST MEM
J 0
(-3275 3625);
DISPLAY 0.744681 (-3275 3625);
PAINT WHITE (-3275 3625);
DISPLAY INVISIBLE (-3275 3625);
FORCEPROP 2 LAST CDS_LIB pure_quanta
J 2
(-3250 3475);
DISPLAY INVISIBLE (-3250 3475);
FORCEPROP 1 LAST WATTAGE 1/16W
J 0
(-3175 3400);
DISPLAY 0.489362 (-3175 3400);
PAINT SKYBLUE (-3175 3400);
DISPLAY INVISIBLE (-3175 3400);
FORCEPROP 1 LAST MATERIAL CHIP
J 0
(-3425 3450);
DISPLAY 0.489362 (-3425 3450);
PAINT SKYBLUE (-3425 3450);
DISPLAY INVISIBLE (-3425 3450);
FORCEPROP 1 LAST TOLERANCE 5%
J 2
(-3125 3450);
DISPLAY 0.489362 (-3125 3450);
PAINT SKYBLUE (-3125 3450);
DISPLAY INVISIBLE (-3125 3450);
FORCEPROP 1 LAST PACK_TYPE 0402LF
J 0
(-3425 3400);
DISPLAY 0.489362 (-3425 3400);
PAINT SKYBLUE (-3425 3400);
DISPLAY INVISIBLE (-3425 3400);
FORCEPROP 1 LAST PATH I81
J 2
(-3200 3625);
DISPLAY 0.978723 (-3200 3625);
PAINT WHITE (-3200 3625);
DISPLAY INVISIBLE (-3200 3625);
FORCEPROP 1 LAST PART_NUMBER CS03302JB10
J 0
(-3350 3525);
DISPLAY 0.489362 (-3350 3525);
PAINT SKYBLUE (-3350 3525);
DISPLAY INVISIBLE (-3350 3525);
FORCEADD Q_RES..1
R 2
(-3250 3575);
FORCEPROP 1 LAST LOCATION R183
J 2
(-3375 3575);
DISPLAY 0.489362 (-3375 3575);
PAINT SKYBLUE (-3375 3575);
FORCEPROP 0 LAST $SEC 1
J 0
(-3375 3625);
DISPLAY 0.680851 (-3375 3625);
PAINT MONO (-3375 3625);
DISPLAY INVISIBLE (-3375 3625);
FORCEPROP 0 LAST CDS_SEC 1
J 0
(-3375 3625);
DISPLAY 1.021277 (-3375 3625);
DISPLAY INVISIBLE (-3375 3625);
FORCEPROP 1 LASTPIN (-3150 3575) $PN 1
J 2
(-3162 3587);
DISPLAY 0.489362 (-3162 3587);
PAINT MONO (-3162 3587);
FORCEPROP 1 LASTPIN (-3350 3575) $PN 2
J 2
(-3312 3587);
DISPLAY 0.489362 (-3312 3587);
PAINT MONO (-3312 3587);
FORCEPROP 1 LAST VALUE 0
J 0
(-3125 3575);
DISPLAY 0.489362 (-3125 3575);
PAINT SKYBLUE (-3125 3575);
FORCEPROP 1 LAST PACK_TYPE 0402LF
J 0
(-3425 3500);
DISPLAY 0.489362 (-3425 3500);
PAINT SKYBLUE (-3425 3500);
DISPLAY INVISIBLE (-3425 3500);
FORCEPROP 1 LAST TOLERANCE 5%
J 2
(-3125 3550);
DISPLAY 0.489362 (-3125 3550);
PAINT SKYBLUE (-3125 3550);
DISPLAY INVISIBLE (-3125 3550);
FORCEPROP 1 LAST MATERIAL CHIP
J 0
(-3425 3550);
DISPLAY 0.489362 (-3425 3550);
PAINT SKYBLUE (-3425 3550);
DISPLAY INVISIBLE (-3425 3550);
FORCEPROP 1 LAST WATTAGE 1/16W
J 0
(-3175 3500);
DISPLAY 0.489362 (-3175 3500);
PAINT SKYBLUE (-3175 3500);
DISPLAY INVISIBLE (-3175 3500);
FORCEPROP 2 LAST CDS_LIB pure_quanta
J 0
(-3250 3575);
DISPLAY INVISIBLE (-3250 3575);
FORCEPROP 2 LAST BOM_COST MEM
J 0
(-3275 3725);
DISPLAY 0.744681 (-3275 3725);
PAINT WHITE (-3275 3725);
DISPLAY INVISIBLE (-3275 3725);
FORCEPROP 1 LAST PATH I82
J 2
(-3200 3725);
DISPLAY 0.978723 (-3200 3725);
PAINT WHITE (-3200 3725);
DISPLAY INVISIBLE (-3200 3725);
FORCEPROP 1 LAST PART_NUMBER CS00002JB13
J 0
(-3350 3625);
DISPLAY 0.489362 (-3350 3625);
PAINT SKYBLUE (-3350 3625);
DISPLAY INVISIBLE (-3350 3625);
FORCEADD Q_RES..1
R 2
(-3250 3675);
FORCEPROP 1 LAST LOCATION R6054
J 2
(-3375 3675);
DISPLAY 0.489362 (-3375 3675);
PAINT SKYBLUE (-3375 3675);
FORCEPROP 0 LAST $SEC 1
J 0
(-3375 3725);
DISPLAY 0.680851 (-3375 3725);
PAINT MONO (-3375 3725);
DISPLAY INVISIBLE (-3375 3725);
FORCEPROP 0 LAST CDS_SEC 1
J 0
(-3375 3725);
DISPLAY 1.021277 (-3375 3725);
DISPLAY INVISIBLE (-3375 3725);
FORCEPROP 1 LASTPIN (-3150 3675) $PN 1
J 2
(-3162 3687);
DISPLAY 0.489362 (-3162 3687);
PAINT MONO (-3162 3687);
FORCEPROP 1 LASTPIN (-3350 3675) $PN 2
J 2
(-3312 3687);
DISPLAY 0.489362 (-3312 3687);
PAINT MONO (-3312 3687);
FORCEPROP 1 LAST VALUE 0
J 0
(-3125 3675);
DISPLAY 0.489362 (-3125 3675);
PAINT SKYBLUE (-3125 3675);
FORCEPROP 1 LAST PACK_TYPE 0402LF
J 0
(-3425 3600);
DISPLAY 0.489362 (-3425 3600);
PAINT SKYBLUE (-3425 3600);
DISPLAY INVISIBLE (-3425 3600);
FORCEPROP 1 LAST TOLERANCE 5%
J 2
(-3125 3650);
DISPLAY 0.489362 (-3125 3650);
PAINT SKYBLUE (-3125 3650);
DISPLAY INVISIBLE (-3125 3650);
FORCEPROP 1 LAST MATERIAL CHIP
J 0
(-3425 3650);
DISPLAY 0.489362 (-3425 3650);
PAINT SKYBLUE (-3425 3650);
DISPLAY INVISIBLE (-3425 3650);
FORCEPROP 1 LAST WATTAGE 1/16W
J 0
(-3175 3600);
DISPLAY 0.489362 (-3175 3600);
PAINT SKYBLUE (-3175 3600);
DISPLAY INVISIBLE (-3175 3600);
FORCEPROP 2 LAST CDS_LIB pure_quanta
J 0
(-3250 3675);
DISPLAY INVISIBLE (-3250 3675);
FORCEPROP 2 LAST BOM_COST MEM
J 0
(-3275 3825);
DISPLAY 0.744681 (-3275 3825);
PAINT WHITE (-3275 3825);
DISPLAY INVISIBLE (-3275 3825);
FORCEPROP 1 LAST PATH I83
J 2
(-3200 3825);
DISPLAY 0.978723 (-3200 3825);
PAINT WHITE (-3200 3825);
DISPLAY INVISIBLE (-3200 3825);
FORCEPROP 1 LAST PART_NUMBER CS00002JB13
J 0
(-3350 3725);
DISPLAY 0.489362 (-3350 3725);
PAINT SKYBLUE (-3350 3725);
DISPLAY INVISIBLE (-3350 3725);
FORCEADD Q_RES..1
R 2
(-3250 3725);
FORCEPROP 1 LAST LOCATION R275
J 2
(-3375 3725);
DISPLAY 0.489362 (-3375 3725);
PAINT SKYBLUE (-3375 3725);
FORCEPROP 0 LAST $SEC 1
J 0
(-3375 3775);
DISPLAY 0.680851 (-3375 3775);
PAINT MONO (-3375 3775);
DISPLAY INVISIBLE (-3375 3775);
FORCEPROP 0 LAST CDS_SEC 1
J 0
(-3375 3775);
DISPLAY 1.021277 (-3375 3775);
DISPLAY INVISIBLE (-3375 3775);
FORCEPROP 1 LASTPIN (-3150 3725) $PN 1
J 2
(-3162 3737);
DISPLAY 0.489362 (-3162 3737);
PAINT MONO (-3162 3737);
FORCEPROP 1 LASTPIN (-3350 3725) $PN 2
J 2
(-3312 3737);
DISPLAY 0.489362 (-3312 3737);
PAINT MONO (-3312 3737);
FORCEPROP 1 LAST VALUE 33
J 0
(-3125 3725);
DISPLAY 0.489362 (-3125 3725);
PAINT SKYBLUE (-3125 3725);
FORCEPROP 2 LAST BOM_COST MEM
J 0
(-3275 3875);
DISPLAY 0.744681 (-3275 3875);
PAINT WHITE (-3275 3875);
DISPLAY INVISIBLE (-3275 3875);
FORCEPROP 2 LAST CDS_LIB pure_quanta
J 0
(-3250 3725);
DISPLAY INVISIBLE (-3250 3725);
FORCEPROP 1 LAST WATTAGE 1/16W
J 0
(-3175 3650);
DISPLAY 0.489362 (-3175 3650);
PAINT SKYBLUE (-3175 3650);
DISPLAY INVISIBLE (-3175 3650);
FORCEPROP 1 LAST MATERIAL CHIP
J 0
(-3425 3700);
DISPLAY 0.489362 (-3425 3700);
PAINT SKYBLUE (-3425 3700);
DISPLAY INVISIBLE (-3425 3700);
FORCEPROP 1 LAST TOLERANCE 5%
J 2
(-3125 3700);
DISPLAY 0.489362 (-3125 3700);
PAINT SKYBLUE (-3125 3700);
DISPLAY INVISIBLE (-3125 3700);
FORCEPROP 1 LAST PACK_TYPE 0402LF
J 0
(-3425 3650);
DISPLAY 0.489362 (-3425 3650);
PAINT SKYBLUE (-3425 3650);
DISPLAY INVISIBLE (-3425 3650);
FORCEPROP 1 LAST PATH I84
J 2
(-3200 3875);
DISPLAY 0.978723 (-3200 3875);
PAINT WHITE (-3200 3875);
DISPLAY INVISIBLE (-3200 3875);
FORCEPROP 1 LAST PART_NUMBER CS03302JB10
J 0
(-3350 3775);
DISPLAY 0.489362 (-3350 3775);
PAINT SKYBLUE (-3350 3775);
DISPLAY INVISIBLE (-3350 3775);
FORCEADD Q_RES..1
R 2
(-3250 3825);
FORCEPROP 1 LAST LOCATION R6053
J 2
(-3375 3825);
DISPLAY 0.489362 (-3375 3825);
PAINT SKYBLUE (-3375 3825);
FORCEPROP 0 LAST $SEC 1
J 0
(-3375 3875);
DISPLAY 0.680851 (-3375 3875);
PAINT MONO (-3375 3875);
DISPLAY INVISIBLE (-3375 3875);
FORCEPROP 0 LAST CDS_SEC 1
J 0
(-3375 3875);
DISPLAY 1.021277 (-3375 3875);
DISPLAY INVISIBLE (-3375 3875);
FORCEPROP 1 LASTPIN (-3150 3825) $PN 1
J 2
(-3162 3837);
DISPLAY 0.489362 (-3162 3837);
PAINT MONO (-3162 3837);
FORCEPROP 1 LASTPIN (-3350 3825) $PN 2
J 2
(-3312 3837);
DISPLAY 0.489362 (-3312 3837);
PAINT MONO (-3312 3837);
FORCEPROP 1 LAST VALUE 0
J 0
(-3125 3825);
DISPLAY 0.489362 (-3125 3825);
PAINT SKYBLUE (-3125 3825);
FORCEPROP 2 LAST CDS_LIB pure_quanta
J 0
(-3250 3825);
DISPLAY INVISIBLE (-3250 3825);
FORCEPROP 2 LAST BOM_COST MEM
J 0
(-3275 3975);
DISPLAY 0.744681 (-3275 3975);
PAINT WHITE (-3275 3975);
DISPLAY INVISIBLE (-3275 3975);
FORCEPROP 1 LAST WATTAGE 1/16W
J 0
(-3175 3750);
DISPLAY 0.489362 (-3175 3750);
PAINT SKYBLUE (-3175 3750);
DISPLAY INVISIBLE (-3175 3750);
FORCEPROP 1 LAST MATERIAL CHIP
J 0
(-3425 3800);
DISPLAY 0.489362 (-3425 3800);
PAINT SKYBLUE (-3425 3800);
DISPLAY INVISIBLE (-3425 3800);
FORCEPROP 1 LAST TOLERANCE 5%
J 2
(-3125 3800);
DISPLAY 0.489362 (-3125 3800);
PAINT SKYBLUE (-3125 3800);
DISPLAY INVISIBLE (-3125 3800);
FORCEPROP 1 LAST PACK_TYPE 0402LF
J 0
(-3425 3750);
DISPLAY 0.489362 (-3425 3750);
PAINT SKYBLUE (-3425 3750);
DISPLAY INVISIBLE (-3425 3750);
FORCEPROP 1 LAST PATH I85
J 2
(-3200 3975);
DISPLAY 0.978723 (-3200 3975);
PAINT WHITE (-3200 3975);
DISPLAY INVISIBLE (-3200 3975);
FORCEPROP 1 LAST PART_NUMBER CS00002JB13
J 0
(-3350 3875);
DISPLAY 0.489362 (-3350 3875);
PAINT SKYBLUE (-3350 3875);
DISPLAY INVISIBLE (-3350 3875);
FORCEADD Q_RES..1
R 2
(-3250 3925);
FORCEPROP 1 LAST LOCATION R958
J 2
(-3375 3925);
DISPLAY 0.489362 (-3375 3925);
PAINT SKYBLUE (-3375 3925);
FORCEPROP 0 LAST $SEC 1
J 2
(-3375 3950);
DISPLAY 0.680851 (-3375 3950);
PAINT MONO (-3375 3950);
DISPLAY INVISIBLE (-3375 3950);
FORCEPROP 0 LAST CDS_SEC 1
J 2
(-3375 3950);
DISPLAY 0.680851 (-3375 3950);
DISPLAY INVISIBLE (-3375 3950);
FORCEPROP 1 LASTPIN (-3150 3925) $PN 1
J 2
(-3162 3937);
DISPLAY 0.489362 (-3162 3937);
PAINT MONO (-3162 3937);
FORCEPROP 1 LASTPIN (-3350 3925) $PN 2
J 2
(-3312 3937);
DISPLAY 0.489362 (-3312 3937);
PAINT MONO (-3312 3937);
FORCEPROP 1 LAST VALUE 33
J 0
(-3125 3925);
DISPLAY 0.489362 (-3125 3925);
PAINT SKYBLUE (-3125 3925);
FORCEPROP 2 LAST BOM_COST MEM
J 0
(-3275 4075);
DISPLAY 0.744681 (-3275 4075);
PAINT WHITE (-3275 4075);
DISPLAY INVISIBLE (-3275 4075);
FORCEPROP 2 LAST CDS_LIB pure_quanta
J 2
(-3250 3925);
DISPLAY INVISIBLE (-3250 3925);
FORCEPROP 1 LAST WATTAGE 1/16W
J 0
(-3175 3850);
DISPLAY 0.489362 (-3175 3850);
PAINT SKYBLUE (-3175 3850);
DISPLAY INVISIBLE (-3175 3850);
FORCEPROP 1 LAST MATERIAL CHIP
J 0
(-3425 3900);
DISPLAY 0.489362 (-3425 3900);
PAINT SKYBLUE (-3425 3900);
DISPLAY INVISIBLE (-3425 3900);
FORCEPROP 1 LAST TOLERANCE 5%
J 2
(-3125 3900);
DISPLAY 0.489362 (-3125 3900);
PAINT SKYBLUE (-3125 3900);
DISPLAY INVISIBLE (-3125 3900);
FORCEPROP 1 LAST PACK_TYPE 0402LF
J 0
(-3425 3850);
DISPLAY 0.489362 (-3425 3850);
PAINT SKYBLUE (-3425 3850);
DISPLAY INVISIBLE (-3425 3850);
FORCEPROP 1 LAST PATH I86
J 2
(-3200 4075);
DISPLAY 0.978723 (-3200 4075);
PAINT WHITE (-3200 4075);
DISPLAY INVISIBLE (-3200 4075);
FORCEPROP 1 LAST PART_NUMBER CS03302JB10
J 0
(-3350 3975);
DISPLAY 0.489362 (-3350 3975);
PAINT SKYBLUE (-3350 3975);
DISPLAY INVISIBLE (-3350 3975);
FORCEADD OFFPAGE..1
R 2
(-2325 3525);
FORCEPROP 2 LAST $XR0 27 
J 0
(-2139 3525);
DISPLAY 0.638298 (-2139 3525);
PAINT MONO (-2139 3525);
FORCEPROP 2 LAST CDS_LIB standard
J 0
(-2325 3525);
DISPLAY INVISIBLE (-2325 3525);
FORCEPROP 1 LAST OFFPAGE TRUE
J 2
(-2650 3400);
DISPLAY 0.872340 (-2650 3400);
PAINT GREEN (-2650 3400);
DISPLAY INVISIBLE (-2650 3400);
FORCEPROP 1 LAST COMMENT_BODY TRUE
J 2
(-2450 3425);
DISPLAY 0.872340 (-2450 3425);
PAINT GREEN (-2450 3425);
DISPLAY INVISIBLE (-2450 3425);
FORCEPROP 2 LAST PATH I87
J 0
(-2125 3575);
DISPLAY 0.680851 (-2125 3575);
DISPLAY INVISIBLE (-2125 3575);
FORCEADD OFFPAGE..2
(-2325 3475);
FORCEPROP 2 LAST $XR0 131 
J 0
(-2136 3475);
DISPLAY 0.638298 (-2136 3475);
PAINT MONO (-2136 3475);
FORCEPROP 2 LAST CDS_LIB standard
J 0
(-2325 3475);
DISPLAY INVISIBLE (-2325 3475);
FORCEPROP 1 LAST OFFPAGE TRUE
J 0
(-2000 3350);
DISPLAY 0.872340 (-2000 3350);
PAINT GREEN (-2000 3350);
DISPLAY INVISIBLE (-2000 3350);
FORCEPROP 1 LAST COMMENT_BODY TRUE
J 0
(-2370 3380);
DISPLAY 0.872340 (-2370 3380);
PAINT GREEN (-2370 3380);
DISPLAY INVISIBLE (-2370 3380);
FORCEPROP 2 LAST PATH I88
J 0
(-2125 3525);
DISPLAY 0.680851 (-2125 3525);
DISPLAY INVISIBLE (-2125 3525);
FORCEADD OFFPAGE..1
R 2
(-2325 3675);
FORCEPROP 2 LAST $XR1 132 
J 0
(-2019 3675);
DISPLAY 0.638298 (-2019 3675);
PAINT MONO (-2019 3675);
FORCEPROP 2 LAST $XR0 131 
J 0
(-2139 3675);
DISPLAY 0.638298 (-2139 3675);
PAINT MONO (-2139 3675);
FORCEPROP 2 LAST CDS_LIB standard
J 0
(-2325 3675);
DISPLAY INVISIBLE (-2325 3675);
FORCEPROP 1 LAST OFFPAGE TRUE
J 2
(-2650 3550);
DISPLAY 0.872340 (-2650 3550);
PAINT GREEN (-2650 3550);
DISPLAY INVISIBLE (-2650 3550);
FORCEPROP 1 LAST COMMENT_BODY TRUE
J 2
(-2450 3575);
DISPLAY 0.872340 (-2450 3575);
PAINT GREEN (-2450 3575);
DISPLAY INVISIBLE (-2450 3575);
FORCEPROP 2 LAST PATH I89
J 0
(-2125 3725);
DISPLAY 0.680851 (-2125 3725);
DISPLAY INVISIBLE (-2125 3725);
FORCEADD OFFPAGE..1
(-7300 4025);
FORCEPROP 2 LAST $XR1 207 
J 0
(-7641 4025);
DISPLAY 0.638298 (-7641 4025);
PAINT MONO (-7641 4025);
FORCEPROP 2 LAST $XR0 83 
J 0
(-7521 4025);
DISPLAY 0.638298 (-7521 4025);
PAINT MONO (-7521 4025);
FORCEPROP 2 LAST CDS_LIB standard
J 0
(-7300 4025);
DISPLAY INVISIBLE (-7300 4025);
FORCEPROP 1 LAST OFFPAGE TRUE
J 0
(-6975 3900);
DISPLAY 0.872340 (-6975 3900);
PAINT GREEN (-6975 3900);
DISPLAY INVISIBLE (-6975 3900);
FORCEPROP 1 LAST COMMENT_BODY TRUE
J 0
(-7175 3925);
DISPLAY 0.872340 (-7175 3925);
PAINT GREEN (-7175 3925);
DISPLAY INVISIBLE (-7175 3925);
FORCEPROP 2 LAST PATH I9
J 0
(-7500 4075);
DISPLAY 0.680851 (-7500 4075);
DISPLAY INVISIBLE (-7500 4075);
FORCEADD OFFPAGE..2
(-2325 3725);
FORCEPROP 2 LAST $XR0 187 
J 0
(-2136 3725);
DISPLAY 0.638298 (-2136 3725);
PAINT MONO (-2136 3725);
FORCEPROP 2 LAST CDS_LIB standard
J 0
(-2325 3725);
DISPLAY INVISIBLE (-2325 3725);
FORCEPROP 1 LAST OFFPAGE TRUE
J 0
(-2000 3600);
DISPLAY 0.872340 (-2000 3600);
PAINT GREEN (-2000 3600);
DISPLAY INVISIBLE (-2000 3600);
FORCEPROP 1 LAST COMMENT_BODY TRUE
J 0
(-2370 3630);
DISPLAY 0.872340 (-2370 3630);
PAINT GREEN (-2370 3630);
DISPLAY INVISIBLE (-2370 3630);
FORCEPROP 2 LAST PATH I90
J 0
(-2125 3775);
DISPLAY 0.680851 (-2125 3775);
DISPLAY INVISIBLE (-2125 3775);
FORCEADD OFFPAGE..1
R 2
(-2325 3575);
FORCEPROP 2 LAST $XR0 27 
J 0
(-2139 3575);
DISPLAY 0.638298 (-2139 3575);
PAINT MONO (-2139 3575);
FORCEPROP 2 LAST CDS_LIB standard
J 0
(-2325 3575);
DISPLAY INVISIBLE (-2325 3575);
FORCEPROP 1 LAST OFFPAGE TRUE
J 2
(-2650 3450);
DISPLAY 0.872340 (-2650 3450);
PAINT GREEN (-2650 3450);
DISPLAY INVISIBLE (-2650 3450);
FORCEPROP 1 LAST COMMENT_BODY TRUE
J 2
(-2450 3475);
DISPLAY 0.872340 (-2450 3475);
PAINT GREEN (-2450 3475);
DISPLAY INVISIBLE (-2450 3475);
FORCEPROP 2 LAST PATH I91
J 0
(-2125 3625);
DISPLAY 0.680851 (-2125 3625);
DISPLAY INVISIBLE (-2125 3625);
FORCEADD OFFPAGE..2
(-2325 3625);
FORCEPROP 2 LAST $XR0 85 
J 0
(-2136 3625);
DISPLAY 0.638298 (-2136 3625);
PAINT MONO (-2136 3625);
FORCEPROP 2 LAST CDS_LIB standard
J 0
(-2325 3625);
DISPLAY INVISIBLE (-2325 3625);
FORCEPROP 1 LAST OFFPAGE TRUE
J 0
(-2000 3500);
DISPLAY 0.872340 (-2000 3500);
PAINT GREEN (-2000 3500);
DISPLAY INVISIBLE (-2000 3500);
FORCEPROP 1 LAST COMMENT_BODY TRUE
J 0
(-2370 3530);
DISPLAY 0.872340 (-2370 3530);
PAINT GREEN (-2370 3530);
DISPLAY INVISIBLE (-2370 3530);
FORCEPROP 2 LAST PATH I92
J 0
(-2125 3675);
DISPLAY 0.680851 (-2125 3675);
DISPLAY INVISIBLE (-2125 3675);
FORCEADD OFFPAGE..1
R 2
(-2325 3875);
FORCEPROP 2 LAST $XR1 210 
J 0
(-2049 3875);
DISPLAY 0.638298 (-2049 3875);
PAINT MONO (-2049 3875);
FORCEPROP 2 LAST $XR0 83 
J 0
(-2139 3875);
DISPLAY 0.638298 (-2139 3875);
PAINT MONO (-2139 3875);
FORCEPROP 2 LAST CDS_LIB standard
J 0
(-2325 3875);
DISPLAY INVISIBLE (-2325 3875);
FORCEPROP 1 LAST OFFPAGE TRUE
J 2
(-2650 3750);
DISPLAY 0.872340 (-2650 3750);
PAINT GREEN (-2650 3750);
DISPLAY INVISIBLE (-2650 3750);
FORCEPROP 1 LAST COMMENT_BODY TRUE
J 2
(-2450 3775);
DISPLAY 0.872340 (-2450 3775);
PAINT GREEN (-2450 3775);
DISPLAY INVISIBLE (-2450 3775);
FORCEPROP 2 LAST PATH I93
J 0
(-2025 3925);
DISPLAY 0.680851 (-2025 3925);
DISPLAY INVISIBLE (-2025 3925);
FORCEADD OFFPAGE..2
(-2325 3925);
FORCEPROP 2 LAST $XR0 136 
J 0
(-2136 3925);
DISPLAY 0.638298 (-2136 3925);
PAINT MONO (-2136 3925);
FORCEPROP 2 LAST CDS_LIB standard
J 0
(-2325 3925);
DISPLAY INVISIBLE (-2325 3925);
FORCEPROP 1 LAST OFFPAGE TRUE
J 0
(-2000 3800);
DISPLAY 0.872340 (-2000 3800);
PAINT GREEN (-2000 3800);
DISPLAY INVISIBLE (-2000 3800);
FORCEPROP 1 LAST COMMENT_BODY TRUE
J 0
(-2370 3830);
DISPLAY 0.872340 (-2370 3830);
PAINT GREEN (-2370 3830);
DISPLAY INVISIBLE (-2370 3830);
FORCEPROP 2 LAST PATH I94
J 0
(-1875 3975);
DISPLAY 0.680851 (-1875 3975);
DISPLAY INVISIBLE (-1875 3975);
FORCEADD OFFPAGE..1
R 2
(-2325 3975);
FORCEPROP 2 LAST $XR1 224 
J 0
(-2049 3975);
DISPLAY 0.638298 (-2049 3975);
PAINT MONO (-2049 3975);
FORCEPROP 2 LAST $XR0 83 
J 0
(-2139 3975);
DISPLAY 0.638298 (-2139 3975);
PAINT MONO (-2139 3975);
FORCEPROP 2 LAST CDS_LIB standard
J 0
(-2325 3975);
DISPLAY INVISIBLE (-2325 3975);
FORCEPROP 1 LAST OFFPAGE TRUE
J 2
(-2650 3850);
DISPLAY 0.872340 (-2650 3850);
PAINT GREEN (-2650 3850);
DISPLAY INVISIBLE (-2650 3850);
FORCEPROP 1 LAST COMMENT_BODY TRUE
J 2
(-2450 3875);
DISPLAY 0.872340 (-2450 3875);
PAINT GREEN (-2450 3875);
DISPLAY INVISIBLE (-2450 3875);
FORCEPROP 2 LAST PATH I95
J 0
(-2025 4025);
DISPLAY 0.680851 (-2025 4025);
DISPLAY INVISIBLE (-2025 4025);
FORCEADD OFFPAGE..1
R 2
(-2325 3825);
FORCEPROP 2 LAST $XR0 144 
J 0
(-2139 3825);
DISPLAY 0.638298 (-2139 3825);
PAINT MONO (-2139 3825);
FORCEPROP 2 LAST CDS_LIB standard
J 0
(-2325 3825);
DISPLAY INVISIBLE (-2325 3825);
FORCEPROP 1 LAST OFFPAGE TRUE
J 2
(-2650 3700);
DISPLAY 0.872340 (-2650 3700);
PAINT GREEN (-2650 3700);
DISPLAY INVISIBLE (-2650 3700);
FORCEPROP 1 LAST COMMENT_BODY TRUE
J 2
(-2450 3725);
DISPLAY 0.872340 (-2450 3725);
PAINT GREEN (-2450 3725);
DISPLAY INVISIBLE (-2450 3725);
FORCEPROP 2 LAST PATH I96
J 0
(-2025 3875);
DISPLAY 0.680851 (-2025 3875);
DISPLAY INVISIBLE (-2025 3875);
FORCEADD UNIVERSAL_POWER..1
R 2
(-1575 1175);
FORCEPROP 3 LASTPIN (-1575 1125) SIG_NAME P3V3_AUX\g
J 0
(-1565 1135);
DISPLAY 0.659574 (-1565 1135);
PAINT MONO (-1565 1135);
DISPLAY INVISIBLE (-1565 1135);
FORCEPROP 1 LAST HDL_POWER P3V3_AUX
J 1
(-1575 1225);
DISPLAY 0.489362 (-1575 1225);
PAINT GREEN (-1575 1225);
FORCEPROP 2 LAST CDS_LIB pure_quanta_power
J 0
(-1575 1175);
DISPLAY INVISIBLE (-1575 1175);
FORCEPROP 1 LAST PATH I97
J 2
(-1625 1200);
DISPLAY 0.872340 (-1625 1200);
PAINT AQUA (-1625 1200);
DISPLAY INVISIBLE (-1625 1200);
FORCEADD VCC_CORE..1
(-1550 1900);
FORCEPROP 3 LASTPIN (-1550 1850) SIG_NAME P1V8_AUX\g
J 0
(-1540 1860);
DISPLAY 0.659574 (-1540 1860);
PAINT MONO (-1540 1860);
DISPLAY INVISIBLE (-1540 1860);
FORCEPROP 1 LAST HDL_POWER P1V8_AUX
J 1
(-1550 1950);
DISPLAY 0.489362 (-1550 1950);
PAINT GREEN (-1550 1950);
FORCEPROP 2 LAST CDS_LIB pure_quanta_power
J 0
(-1550 1900);
DISPLAY INVISIBLE (-1550 1900);
FORCEPROP 1 LAST PATH I98
J 0
(-1500 1925);
DISPLAY 0.872340 (-1500 1925);
PAINT AQUA (-1500 1925);
DISPLAY INVISIBLE (-1500 1925);
FORCEADD Q_RES..1
(-3200 4425);
FORCEPROP 1 LAST LOCATION R6052
J 0
(-3075 4425);
DISPLAY 0.489362 (-3075 4425);
PAINT SKYBLUE (-3075 4425);
FORCEPROP 0 LAST $SEC 1
J 2
(-3075 4475);
DISPLAY 0.680851 (-3075 4475);
PAINT MONO (-3075 4475);
DISPLAY INVISIBLE (-3075 4475);
FORCEPROP 0 LAST CDS_SEC 1
J 2
(-3075 4475);
DISPLAY 1.021277 (-3075 4475);
DISPLAY INVISIBLE (-3075 4475);
FORCEPROP 1 LASTPIN (-3300 4425) $PN 1
J 0
(-3288 4437);
DISPLAY 0.489362 (-3288 4437);
PAINT MONO (-3288 4437);
FORCEPROP 1 LASTPIN (-3100 4425) $PN 2
J 0
(-3138 4437);
DISPLAY 0.489362 (-3138 4437);
PAINT MONO (-3138 4437);
FORCEPROP 1 LAST VALUE 0
J 2
(-3325 4425);
DISPLAY 0.489362 (-3325 4425);
PAINT SKYBLUE (-3325 4425);
FORCEPROP 2 LAST BOM_COST MEM
J 2
(-3175 4575);
DISPLAY 0.744681 (-3175 4575);
PAINT WHITE (-3175 4575);
DISPLAY INVISIBLE (-3175 4575);
FORCEPROP 2 LAST CDS_LIB pure_quanta
J 2
(-3200 4425);
DISPLAY INVISIBLE (-3200 4425);
FORCEPROP 1 LAST WATTAGE 1/16W
J 2
(-3275 4350);
DISPLAY 0.489362 (-3275 4350);
PAINT SKYBLUE (-3275 4350);
DISPLAY INVISIBLE (-3275 4350);
FORCEPROP 1 LAST MATERIAL CHIP
J 2
(-3025 4400);
DISPLAY 0.489362 (-3025 4400);
PAINT SKYBLUE (-3025 4400);
DISPLAY INVISIBLE (-3025 4400);
FORCEPROP 1 LAST TOLERANCE 5%
J 0
(-3325 4400);
DISPLAY 0.489362 (-3325 4400);
PAINT SKYBLUE (-3325 4400);
DISPLAY INVISIBLE (-3325 4400);
FORCEPROP 1 LAST PACK_TYPE 0402LF
J 2
(-3025 4350);
DISPLAY 0.489362 (-3025 4350);
PAINT SKYBLUE (-3025 4350);
DISPLAY INVISIBLE (-3025 4350);
FORCEPROP 1 LAST PATH I99
J 0
(-3250 4575);
DISPLAY 0.978723 (-3250 4575);
PAINT WHITE (-3250 4575);
DISPLAY INVISIBLE (-3250 4575);
FORCEPROP 1 LAST PART_NUMBER CS00002JB13
J 2
(-3100 4475);
DISPLAY 0.489362 (-3100 4475);
PAINT SKYBLUE (-3100 4475);
DISPLAY INVISIBLE (-3100 4475);
FORCEADD QUANTA_TITLE_BLOCK_C..1
(0 0);
FORCEPROP 0 LAST CDS_CON_LAST_MODIFIED Thu Sep 14 16:12:39 2023
J 0
(-1885 15);
DISPLAY INVISIBLE (-1885 15);
FORCEPROP 1 LAST CUSTOM_TXT_CDS <CON_LAST_MODIFIED>
J 0
(-1885 15);
DISPLAY 0.978723 (-1885 15);
FORCEPROP 2 LAST CUSTOM_TXT_CDS <XR_PAGE_TITLE>
J 0
(-7890 5250);
DISPLAY 0.638298 (-7890 5250);
PAINT PINK (-7890 5250);
DISPLAY INVISIBLE (-7890 5250);
FORCEPROP 1 LAST CUSTOM_TXT_CDS <NAME_2>
J 0
(-3175 50);
FORCEPROP 1 LAST CUSTOM_TXT_CDS <NAME_1>
J 0
(-3175 175);
FORCEPROP 1 LAST CUSTOM_TXT_CDS <Q_NUMBER>
J 0
(-1403 103);
DISPLAY 1.212766 (-1403 103);
FORCEPROP 1 LAST CUSTOM_TXT_CDS <Q_PROJ>
J 0
(-2382 102);
DISPLAY 1.212766 (-2382 102);
FORCEPROP 1 LAST CUSTOM_TXT_CDS <Q_REV>
J 0
(-184 103);
DISPLAY 1.212766 (-184 103);
FORCEPROP 1 LAST CUSTOM_TXT_CDS <CON_PAGE_NUM> OF <CON_TOTAL_PAGES>
J 0
(-446 18);
DISPLAY 0.978723 (-446 18);
FORCEPROP 1 LAST Q_TITLE FPGA 3/6
J 0
(-9300 50);
DISPLAY 2.446809 (-9300 50);
PAINT GREEN (-9300 50);
FORCEPROP 2 LAST PAGE_BORDER TRUE
J 0
(-7890 5250);
DISPLAY 0.638298 (-7890 5250);
PAINT PINK (-7890 5250);
DISPLAY INVISIBLE (-7890 5250);
FORCEPROP 1 LAST CDS_LMAN_SYM_OUTLINE -9475,6775,100,-125
J 0
(0 0);
DISPLAY 0.468085 (0 0);
PAINT GREEN (0 0);
DISPLAY INVISIBLE (0 0);
FORCEPROP 2 LAST CDS_LIB pure_quanta
J 0
(0 0);
DISPLAY INVISIBLE (0 0);
FORCEPROP 2 LAST CDS_XR_PAGE_TITLE CR-82 : @T6G_MB_LIB.T6G(SCH_1):PAGE82
J 0
(-7890 5250);
DISPLAY 0.638298 (-7890 5250);
PAINT PINK (-7890 5250);
DISPLAY INVISIBLE (-7890 5250);
FORCEPROP 1 LAST Q_DEPT BU9
J 1
(-3763 49);
DISPLAY 1.957447 (-3763 49);
PAINT GREEN (-3763 49);
DISPLAY INVISIBLE (-3763 49);
FORCEPROP 1 LAST COMMENT_BODY TRUE
J 0
(12 -13);
DISPLAY 0.978723 (12 -13);
PAINT GREEN (12 -13);
DISPLAY INVISIBLE (12 -13);
WIRE 16 -1 (-5500 5475)(-6350 5475);
FORCEPROP 2 LAST SIG_NAME FM_CPU1_BMC_RST_R_N
J 0
(-6175 5485);
DISPLAY 0.489362 (-6175 5485);
FORCEPROP 2 LASTPROP $XRERR UNIQUE?
J 0
(-6415 5485);
DISPLAY 0.638298 (-6415 5485);
PAINT MONO (-6415 5485);
DISPLAY INVISIBLE (-6415 5485);
WIRE 16 -1 (-6550 5775)(-7250 5775);
FORCEPROP 2 LAST SIG_NAME IRQ_CPU_BMC_NMI_N
J 0
(-7175 5785);
DISPLAY 0.553191 (-7175 5785);
PAINT WHITE (-7175 5785);
WIRE 16 -1 (-7250 5725)(-6550 5725);
FORCEPROP 2 LAST SIG_NAME CPU0_XTRIG_L5
J 0
(-7175 5735);
DISPLAY 0.489362 (-7175 5735);
WIRE 16 -1 (-7250 5675)(-6550 5675);
FORCEPROP 2 LAST SIG_NAME CPU0_XTRIG_L4
J 0
(-7175 5685);
DISPLAY 0.489362 (-7175 5685);
WIRE 16 -1 (-7250 5625)(-6550 5625);
FORCEPROP 2 LAST SIG_NAME IRQ_SMI_ACTIVE_N
J 0
(-7175 5635);
DISPLAY 0.553191 (-7175 5635);
PAINT WHITE (-7175 5635);
WIRE 16 -1 (-7250 5575)(-6550 5575);
FORCEPROP 2 LAST SIG_NAME IRQ_TPM_SPI_R_N
J 0
(-7175 5585);
DISPLAY 0.553191 (-7175 5585);
PAINT WHITE (-7175 5585);
WIRE 16 -1 (-6550 5325)(-7250 5325);
FORCEPROP 2 LAST SIG_NAME FM_BMC_TPM_PRES_N
J 0
(-7175 5335);
DISPLAY 0.553191 (-7175 5335);
PAINT WHITE (-7175 5335);
WIRE 16 -1 (-6350 5425)(-5500 5425);
FORCEPROP 2 LAST SIG_NAME FM_CPU0_XTRIG_L7
J 0
(-6175 5435);
DISPLAY 0.489362 (-6175 5435);
FORCEPROP 2 LASTPROP $XRERR UNIQUE?
J 0
(-6415 5435);
DISPLAY 0.638298 (-6415 5435);
PAINT MONO (-6415 5435);
DISPLAY INVISIBLE (-6415 5435);
WIRE 16 -1 (-5500 5375)(-6350 5375);
FORCEPROP 2 LAST SIG_NAME FM_BMC_READY_R_N
J 0
(-6175 5385);
DISPLAY 0.553191 (-6175 5385);
PAINT WHITE (-6175 5385);
FORCEPROP 2 LASTPROP $XRERR UNIQUE?
J 0
(-6415 5385);
DISPLAY 0.638298 (-6415 5385);
PAINT MONO (-6415 5385);
DISPLAY INVISIBLE (-6415 5385);
WIRE 16 -1 (-7250 5425)(-6550 5425);
FORCEPROP 2 LAST SIG_NAME CPU0_XTRIG_L7
J 0
(-7175 5435);
DISPLAY 0.489362 (-7175 5435);
WIRE 16 -1 (-6550 5475)(-7250 5475);
FORCEPROP 2 LAST SIG_NAME FM_CPU1_BMC_RST_N
J 0
(-7175 5485);
DISPLAY 0.489362 (-7175 5485);
PAINT SKYBLUE (-7175 5485);
WIRE 16 -1 (-6550 5375)(-7250 5375);
FORCEPROP 2 LAST SIG_NAME FM_BMC_READY_N
J 0
(-7175 5385);
DISPLAY 0.553191 (-7175 5385);
PAINT WHITE (-7175 5385);
WIRE 16 -1 (-6550 5275)(-7250 5275);
FORCEPROP 2 LAST SIG_NAME PVDDCR_CPU0_P0_OCP_N
J 0
(-7175 5285);
DISPLAY 0.489362 (-7175 5285);
WIRE 16 -1 (-6550 5225)(-7250 5225);
FORCEPROP 2 LAST SIG_NAME PVDDCR_CPU1_P0_OCP_N
J 0
(-7175 5235);
DISPLAY 0.489362 (-7175 5235);
WIRE 16 -1 (-7250 4725)(-6550 4725);
FORCEPROP 2 LAST SIG_NAME CPU1_CORETYPE2
J 0
(-7175 4735);
DISPLAY 0.489362 (-7175 4735);
WIRE 16 -1 (-7250 4675)(-6550 4675);
FORCEPROP 2 LAST SIG_NAME FM_PVDDCR_CPU1_P0_EN
J 0
(-7175 4685);
DISPLAY 0.489362 (-7175 4685);
WIRE 16 -1 (-7250 4625)(-5500 4625);
FORCEPROP 2 LAST SIG_NAME FM_LED_PWRGD_PVDDCR_CPU1_P0
J 0
(-7175 4635);
DISPLAY 0.489362 (-7175 4635);
WIRE 16 -1 (-7250 4575)(-6550 4575);
FORCEPROP 2 LAST SIG_NAME CPU1_SP5R2
J 0
(-7175 4585);
DISPLAY 0.489362 (-7175 4585);
WIRE 16 -1 (-7250 4525)(-6550 4525);
FORCEPROP 2 LAST SIG_NAME CPU1_SP5R1
J 0
(-7175 4535);
DISPLAY 0.489362 (-7175 4535);
WIRE 16 -1 (-7250 4375)(-6550 4375);
FORCEPROP 2 LAST SIG_NAME CPU1_CORETYPE1
J 0
(-7175 4385);
DISPLAY 0.489362 (-7175 4385);
WIRE 16 -1 (-7250 4225)(-6550 4225);
FORCEPROP 2 LAST SIG_NAME CPU0_SP5R2
J 0
(-7175 4235);
DISPLAY 0.489362 (-7175 4235);
WIRE 16 -1 (-6550 4175)(-7250 4175);
FORCEPROP 2 LAST SIG_NAME CPU0_SP5R1
J 0
(-7175 4185);
DISPLAY 0.489362 (-7175 4185);
WIRE 16 -1 (-7250 4125)(-6550 4125);
FORCEPROP 2 LAST SIG_NAME CPU1_CORETYPE0
J 0
(-7175 4135);
DISPLAY 0.489362 (-7175 4135);
WIRE 16 -1 (-6550 5175)(-7250 5175);
FORCEPROP 2 LAST SIG_NAME PVDDCR_CPU1_P1_OCP_N
J 0
(-7175 5185);
DISPLAY 0.489362 (-7175 5185);
WIRE 16 -1 (-6350 5575)(-5500 5575);
FORCEPROP 2 LAST SIG_NAME IRQ_TPM_SPI_R1_N
J 0
(-6175 5585);
DISPLAY 0.553191 (-6175 5585);
PAINT WHITE (-6175 5585);
FORCEPROP 2 LASTPROP $XRERR UNIQUE?
J 0
(-6415 5585);
DISPLAY 0.638298 (-6415 5585);
PAINT MONO (-6415 5585);
DISPLAY INVISIBLE (-6415 5585);
WIRE 16 -1 (-6350 5625)(-5500 5625);
FORCEPROP 2 LAST SIG_NAME IRQ_SMI_ACTIVE_N_R
J 0
(-6175 5635);
DISPLAY 0.553191 (-6175 5635);
PAINT WHITE (-6175 5635);
FORCEPROP 2 LASTPROP $XRERR UNIQUE?
J 0
(-6415 5635);
DISPLAY 0.638298 (-6415 5635);
PAINT MONO (-6415 5635);
DISPLAY INVISIBLE (-6415 5635);
WIRE 16 -1 (-6350 5675)(-5500 5675);
FORCEPROP 2 LAST SIG_NAME FM_CPU0_XTRIG_L4
J 0
(-6175 5685);
DISPLAY 0.489362 (-6175 5685);
FORCEPROP 2 LASTPROP $XRERR UNIQUE?
J 0
(-6415 5685);
DISPLAY 0.638298 (-6415 5685);
PAINT MONO (-6415 5685);
DISPLAY INVISIBLE (-6415 5685);
WIRE 16 -1 (-6350 5725)(-5500 5725);
FORCEPROP 2 LAST SIG_NAME FM_CPU0_XTRIG_L5
J 0
(-6175 5735);
DISPLAY 0.489362 (-6175 5735);
FORCEPROP 2 LASTPROP $XRERR UNIQUE?
J 0
(-6415 5735);
DISPLAY 0.638298 (-6415 5735);
PAINT MONO (-6415 5735);
DISPLAY INVISIBLE (-6415 5735);
WIRE 16 -1 (-5500 5775)(-6350 5775);
FORCEPROP 2 LAST SIG_NAME IRQ_CPU_BMC_NMI_R_N
J 0
(-6175 5785);
DISPLAY 0.553191 (-6175 5785);
PAINT WHITE (-6175 5785);
FORCEPROP 2 LASTPROP $XRERR UNIQUE?
J 0
(-6415 5785);
DISPLAY 0.638298 (-6415 5785);
PAINT MONO (-6415 5785);
DISPLAY INVISIBLE (-6415 5785);
WIRE 16 -1 (-6350 5825)(-5500 5825);
FORCEPROP 2 LAST SIG_NAME FM_CPU1_XTRIG_L7
J 0
(-6175 5835);
DISPLAY 0.489362 (-6175 5835);
FORCEPROP 2 LASTPROP $XRERR UNIQUE?
J 0
(-6415 5835);
DISPLAY 0.638298 (-6415 5835);
PAINT MONO (-6415 5835);
DISPLAY INVISIBLE (-6415 5835);
WIRE 16 -1 (-7250 5525)(-6550 5525);
FORCEPROP 2 LAST SIG_NAME FM_SMM_CRASHDUMP
J 0
(-7175 5535);
DISPLAY 0.553191 (-7175 5535);
PAINT WHITE (-7175 5535);
WIRE 16 -1 (-3175 1925)(-2875 1925);
WIRE 16 -1 (-3175 1925)(-3175 1975);
WIRE 16 -1 (-3175 1975)(-2875 1975);
WIRE 16 -1 (-3175 1975)(-3175 2025);
WIRE 16 -1 (-3175 2025)(-3175 2075);
WIRE 16 -1 (-3175 2025)(-2875 2025);
WIRE 16 -1 (-3175 2075)(-2875 2075);
WIRE 16 -1 (-3175 2075)(-3175 2125);
WIRE 16 -1 (-3175 2125)(-2875 2125);
WIRE 16 -1 (-3175 2125)(-3175 2175);
WIRE 16 -1 (-3175 2175)(-2875 2175);
WIRE 16 -1 (-3175 2175)(-3175 2225);
WIRE 16 -1 (-3175 2225)(-2875 2225);
WIRE 16 -1 (-3175 2225)(-3175 2275);
WIRE 16 -1 (-3175 2275)(-2875 2275);
WIRE 16 -1 (-3175 2275)(-3175 2325);
WIRE 16 -1 (-3175 2325)(-2875 2325);
WIRE 16 -1 (-3175 2325)(-3175 2375);
WIRE 16 -1 (-3175 2375)(-2875 2375);
WIRE 16 -1 (-3175 2375)(-3175 2425);
WIRE 16 -1 (-3175 2425)(-2875 2425);
WIRE 16 -1 (-3175 2425)(-3175 2475);
WIRE 16 -1 (-3175 2475)(-2875 2475);
WIRE 16 -1 (-3175 2475)(-3175 2550);
WIRE 16 -1 (-6200 2900)(-6200 2850);
WIRE 16 -1 (-6200 2900)(-6400 2900);
WIRE 16 -1 (-6200 2850)(-6200 2800);
WIRE 16 -1 (-6200 2850)(-6400 2850);
WIRE 16 -1 (-6200 2800)(-6200 2750);
WIRE 16 -1 (-6200 2800)(-6400 2800);
WIRE 16 -1 (-6200 2750)(-6200 2700);
WIRE 16 -1 (-6200 2750)(-6400 2750);
WIRE 16 -1 (-6200 2700)(-6200 2650);
WIRE 16 -1 (-6200 2700)(-6400 2700);
WIRE 16 -1 (-6200 2650)(-6200 2600);
WIRE 16 -1 (-6200 2650)(-6400 2650);
WIRE 16 -1 (-6200 2600)(-6400 2600);
WIRE 16 -1 (-6200 2600)(-6200 2550);
WIRE 16 -1 (-6200 2550)(-6200 2500);
WIRE 16 -1 (-6200 2550)(-6400 2550);
WIRE 16 -1 (-6200 2500)(-6200 2450);
WIRE 16 -1 (-6200 2500)(-6400 2500);
WIRE 16 -1 (-6200 2450)(-6200 2400);
WIRE 16 -1 (-6200 2450)(-6400 2450);
WIRE 16 -1 (-6200 2400)(-6200 2350);
WIRE 16 -1 (-6200 2400)(-6400 2400);
WIRE 16 -1 (-6200 2350)(-6200 2300);
WIRE 16 -1 (-6200 2350)(-6400 2350);
WIRE 16 -1 (-6200 2300)(-6200 2250);
WIRE 16 -1 (-6200 2300)(-6400 2300);
WIRE 16 -1 (-6200 2250)(-6200 2200);
WIRE 16 -1 (-6200 2250)(-6400 2250);
WIRE 16 -1 (-6200 2200)(-6200 2150);
WIRE 16 -1 (-6200 2200)(-6400 2200);
WIRE 16 -1 (-6200 2150)(-6200 2100);
WIRE 16 -1 (-6200 2150)(-6400 2150);
WIRE 16 -1 (-6200 2100)(-6200 2050);
WIRE 16 -1 (-6200 2100)(-6400 2100);
WIRE 16 -1 (-6200 2050)(-6400 2050);
WIRE 16 -1 (-6200 2050)(-6200 2000);
WIRE 16 -1 (-6200 2000)(-6200 1950);
WIRE 16 -1 (-6200 2000)(-6400 2000);
WIRE 16 -1 (-6200 1950)(-6200 1900);
WIRE 16 -1 (-6200 1950)(-6400 1950);
WIRE 16 -1 (-6200 1900)(-6200 1850);
WIRE 16 -1 (-6200 1900)(-6400 1900);
WIRE 16 -1 (-6200 1850)(-6200 1800);
WIRE 16 -1 (-6200 1850)(-6400 1850);
WIRE 16 -1 (-6200 1800)(-6200 1750);
WIRE 16 -1 (-6200 1800)(-6400 1800);
WIRE 16 -1 (-6200 1750)(-6200 1700);
WIRE 16 -1 (-6200 1750)(-6400 1750);
WIRE 16 -1 (-6200 1700)(-6200 1650);
WIRE 16 -1 (-6200 1700)(-6400 1700);
WIRE 16 -1 (-6200 1650)(-6200 1600);
WIRE 16 -1 (-6200 1650)(-6400 1650);
WIRE 16 -1 (-6200 1600)(-6200 1550);
WIRE 16 -1 (-6200 1600)(-6400 1600);
WIRE 16 -1 (-6200 1550)(-6400 1550);
WIRE 16 -1 (-6200 1550)(-6200 1500);
WIRE 16 -1 (-6200 1500)(-6200 1450);
WIRE 16 -1 (-6200 1500)(-6400 1500);
WIRE 16 -1 (-6200 1450)(-6200 1400);
WIRE 16 -1 (-6200 1450)(-6400 1450);
WIRE 16 -1 (-6200 1350)(-6200 1400);
WIRE 16 -1 (-6200 1400)(-6400 1400);
WIRE 16 -1 (-6200 1300)(-6200 1350);
WIRE 16 -1 (-6200 1350)(-6400 1350);
WIRE 16 -1 (-6200 1300)(-6200 1250);
WIRE 16 -1 (-6200 1300)(-6400 1300);
WIRE 16 -1 (-6200 1250)(-6200 1200);
WIRE 16 -1 (-6200 1250)(-6400 1250);
WIRE 16 -1 (-6200 1200)(-6200 1150);
WIRE 16 -1 (-6200 1200)(-6400 1200);
WIRE 16 -1 (-6200 1150)(-6200 1100);
WIRE 16 -1 (-6200 1150)(-6400 1150);
WIRE 16 -1 (-6200 1100)(-6200 1050);
WIRE 16 -1 (-6200 1100)(-6400 1100);
WIRE 16 -1 (-6200 1050)(-6400 1050);
WIRE 16 -1 (-6200 1050)(-6200 1000);
WIRE 16 -1 (-6200 1000)(-6200 950);
WIRE 16 -1 (-6200 1000)(-6400 1000);
WIRE 16 -1 (-6200 950)(-6200 900);
WIRE 16 -1 (-6200 950)(-6400 950);
WIRE 16 -1 (-6200 900)(-6200 850);
WIRE 16 -1 (-6200 900)(-6400 900);
WIRE 16 -1 (-6200 850)(-6200 800);
WIRE 16 -1 (-6200 850)(-6400 850);
WIRE 16 -1 (-6200 800)(-6200 750);
WIRE 16 -1 (-6200 800)(-6400 800);
WIRE 16 -1 (-6200 750)(-6200 700);
WIRE 16 -1 (-6200 750)(-6400 750);
WIRE 16 -1 (-6200 700)(-6200 650);
WIRE 16 -1 (-6200 700)(-6400 700);
WIRE 16 -1 (-6200 650)(-6200 600);
WIRE 16 -1 (-6200 650)(-6400 650);
WIRE 16 -1 (-6200 600)(-6200 550);
WIRE 16 -1 (-6200 600)(-6400 600);
WIRE 16 -1 (-6200 550)(-6400 550);
WIRE 16 -1 (-6200 550)(-6200 500);
WIRE 16 -1 (-6200 450)(-6200 500);
WIRE 16 -1 (-6200 500)(-6400 500);
WIRE 16 -1 (-6200 400)(-6200 450);
WIRE 16 -1 (-6200 450)(-6400 450);
WIRE 16 -1 (-6200 400)(-6200 350);
WIRE 16 -1 (-6200 400)(-6400 400);
WIRE 16 -1 (-6200 350)(-6200 300);
WIRE 16 -1 (-6200 350)(-6400 350);
WIRE 16 -1 (-3675 675)(-2875 675);
WIRE 16 -1 (-3675 725)(-3675 675);
WIRE 16 -1 (-3675 725)(-2875 725);
WIRE 16 -1 (-3675 775)(-3675 725);
WIRE 16 -1 (-3675 775)(-2875 775);
WIRE 16 -1 (-3675 825)(-3675 775);
WIRE 16 -1 (-3675 825)(-2875 825);
WIRE 16 -1 (-3675 875)(-3675 825);
WIRE 16 -1 (-3675 875)(-2875 875);
WIRE 16 -1 (-3675 925)(-3675 875);
WIRE 16 -1 (-3675 925)(-2875 925);
WIRE 16 -1 (-3675 975)(-3675 925);
WIRE 16 -1 (-3675 975)(-2875 975);
WIRE 16 -1 (-3675 1025)(-3675 975);
WIRE 16 -1 (-3675 1025)(-2875 1025);
WIRE 16 -1 (-3675 1075)(-3675 1025);
WIRE 16 -1 (-3675 1075)(-2875 1075);
WIRE 16 -1 (-3675 1075)(-3675 1175);
WIRE 16 -1 (-3675 1175)(-2875 1175);
FORCEPROP 0 LAST VOLTAGE 3.3
J 0
(-3175 1175);
PAINT SKYBLUE (-3175 1175);
DISPLAY INVISIBLE (-3175 1175);
WIRE 16 -1 (-3675 1175)(-3675 1225);
WIRE 16 -1 (-3675 1225)(-2875 1225);
FORCEPROP 0 LAST VOLTAGE 3.3
J 0
(-3175 1225);
PAINT SKYBLUE (-3175 1225);
DISPLAY INVISIBLE (-3175 1225);
WIRE 16 -1 (-3675 1225)(-3675 1275);
WIRE 16 -1 (-3675 1275)(-2875 1275);
FORCEPROP 0 LAST VOLTAGE 3.3
J 0
(-3175 1275);
PAINT SKYBLUE (-3175 1275);
DISPLAY INVISIBLE (-3175 1275);
WIRE 16 -1 (-3675 1275)(-3675 1475);
WIRE 16 -1 (-3675 1475)(-2875 1475);
FORCEPROP 0 LAST VOLTAGE 3.3
J 0
(-3175 1475);
PAINT SKYBLUE (-3175 1475);
DISPLAY INVISIBLE (-3175 1475);
WIRE 16 -1 (-3675 1475)(-3675 1525);
WIRE 16 -1 (-3675 1525)(-2875 1525);
FORCEPROP 0 LAST VOLTAGE 3.3
J 0
(-3175 1525);
PAINT SKYBLUE (-3175 1525);
DISPLAY INVISIBLE (-3175 1525);
WIRE 16 -1 (-3675 1525)(-3675 1575);
WIRE 16 -1 (-3675 1575)(-2875 1575);
FORCEPROP 0 LAST VOLTAGE 3.3
J 0
(-3175 1575);
PAINT SKYBLUE (-3175 1575);
DISPLAY INVISIBLE (-3175 1575);
WIRE 16 -1 (-3675 1575)(-3675 1650);
WIRE 16 -1 (-3375 1675)(-2875 1675);
WIRE 16 -1 (-3375 1725)(-3375 1675);
WIRE 16 -1 (-3375 1725)(-2875 1725);
WIRE 16 -1 (-3375 1775)(-3375 1725);
WIRE 16 -1 (-3375 1775)(-2875 1775);
WIRE 16 -1 (-3375 1800)(-3375 1775);
WIRE 16 -1 (-1575 775)(-1575 725);
WIRE 16 -1 (-1575 825)(-1575 775);
WIRE 16 -1 (-1575 775)(-1775 775);
WIRE 16 -1 (-1575 725)(-1575 675);
WIRE 16 -1 (-1575 725)(-1775 725);
WIRE 16 -1 (-1575 675)(-1775 675);
WIRE 16 -1 (-1575 875)(-1575 825);
WIRE 16 -1 (-1575 825)(-1775 825);
WIRE 16 -1 (-1575 925)(-1575 875);
WIRE 16 -1 (-1575 875)(-1775 875);
WIRE 16 -1 (-1575 975)(-1575 925);
WIRE 16 -1 (-1575 925)(-1775 925);
WIRE 16 -1 (-1575 1025)(-1575 975);
WIRE 16 -1 (-1575 975)(-1775 975);
WIRE 16 -1 (-1575 1075)(-1575 1025);
WIRE 16 -1 (-1575 1025)(-1775 1025);
WIRE 16 -1 (-1575 1125)(-1575 1075);
WIRE 16 -1 (-1575 1075)(-1775 1075);
WIRE 16 -1 (-1550 1475)(-1550 1425);
WIRE 16 -1 (-1550 1525)(-1550 1475);
WIRE 16 -1 (-1550 1475)(-1775 1475);
WIRE 16 -1 (-1550 1425)(-1550 1375);
WIRE 16 -1 (-1550 1425)(-1775 1425);
WIRE 16 -1 (-1550 1375)(-1775 1375);
WIRE 16 -1 (-1550 1575)(-1550 1525);
WIRE 16 -1 (-1550 1525)(-1775 1525);
WIRE 16 -1 (-1550 1625)(-1550 1575);
WIRE 16 -1 (-1550 1575)(-1775 1575);
WIRE 16 -1 (-1550 1675)(-1550 1625);
WIRE 16 -1 (-1550 1625)(-1775 1625);
WIRE 16 -1 (-1550 1725)(-1550 1675);
WIRE 16 -1 (-1550 1675)(-1775 1675);
WIRE 16 -1 (-1550 1775)(-1550 1725);
WIRE 16 -1 (-1550 1725)(-1775 1725);
WIRE 16 -1 (-1550 1850)(-1550 1775);
WIRE 16 -1 (-1550 1775)(-1775 1775);
WIRE 16 -1 (-4200 4375)(-3300 4375);
FORCEPROP 2 LAST SIG_NAME FM_PRSNT_CPU0_R_N
J 0
(-4075 4375);
DISPLAY 0.489362 (-4075 4375);
FORCEPROP 2 LASTPROP $XRERR UNIQUE?
J 0
(-4315 4375);
DISPLAY 0.638298 (-4315 4375);
PAINT MONO (-4315 4375);
DISPLAY INVISIBLE (-4315 4375);
WIRE 16 -1 (-2375 3975)(-4200 3975);
FORCEPROP 2 LAST SIG_NAME PVDD11_S3_P1_PMALERT
J 0
(-4075 3985);
DISPLAY 0.489362 (-4075 3985);
WIRE 16 -1 (-3150 3725)(-2375 3725);
FORCEPROP 2 LAST SIG_NAME CLR_CMOS
J 0
(-2950 3735);
DISPLAY 0.617021 (-2950 3735);
WIRE 16 -1 (-2375 3625)(-4200 3625);
FORCEPROP 0 LAST SIG_NAME FM_SMB_RST_E1S_0_N
J 0
(-4075 3635);
DISPLAY 0.489362 (-4075 3635);
WIRE 16 -1 (-3150 3575)(-2375 3575);
FORCEPROP 2 LAST SIG_NAME CPU0_CORETYPE0
J 0
(-2950 3585);
DISPLAY 0.489362 (-2950 3585);
WIRE 16 -1 (-3150 3675)(-2375 3675);
FORCEPROP 2 LAST SIG_NAME FM_OCP_SFF_PWR_GOOD
J 0
(-2950 3685);
DISPLAY 0.553191 (-2950 3685);
WIRE 16 -1 (-3175 3775)(-2375 3775);
FORCEPROP 2 LAST SIG_NAME OCP_V3_2_P3V3_P12V_ADC_R_ALERT
J 0
(-3085 3785);
DISPLAY 0.553191 (-3085 3785);
WIRE 16 -1 (-3375 3775)(-4200 3775);
FORCEPROP 2 LAST SIG_NAME OCP_V3_2_P3V3_P12V_ADC_ALERT
J 0
(-4085 3785);
DISPLAY 0.446809 (-4085 3785);
PAINT WHITE (-4085 3785);
FORCEPROP 2 LASTPROP $XRERR UNIQUE?
J 0
(-4325 3785);
DISPLAY 0.638298 (-4325 3785);
PAINT MONO (-4325 3785);
DISPLAY INVISIBLE (-4325 3785);
WIRE 16 -1 (-3350 3725)(-4200 3725);
FORCEPROP 2 LAST SIG_NAME FM_CLR_CMOS
J 0
(-4075 3735);
DISPLAY 0.489362 (-4075 3735);
FORCEPROP 2 LASTPROP $XRERR UNIQUE?
J 0
(-4315 3735);
DISPLAY 0.638298 (-4315 3735);
PAINT MONO (-4315 3735);
DISPLAY INVISIBLE (-4315 3735);
WIRE 16 -1 (-4200 3675)(-3350 3675);
FORCEPROP 2 LAST SIG_NAME PWRGD_OCP_SFF_PWR_GOOD
J 0
(-4075 3685);
DISPLAY 0.489362 (-4075 3685);
FORCEPROP 2 LASTPROP $XRERR UNIQUE?
J 0
(-4315 3685);
DISPLAY 0.638298 (-4315 3685);
PAINT MONO (-4315 3685);
DISPLAY INVISIBLE (-4315 3685);
WIRE 16 -1 (-4200 3575)(-3350 3575);
FORCEPROP 2 LAST SIG_NAME FM_CPU0_CORETYPE0
J 0
(-4075 3585);
DISPLAY 0.489362 (-4075 3585);
FORCEPROP 2 LASTPROP $XRERR UNIQUE?
J 0
(-4315 3585);
DISPLAY 0.638298 (-4315 3585);
PAINT MONO (-4315 3585);
DISPLAY INVISIBLE (-4315 3585);
WIRE 16 -1 (-4200 3525)(-3350 3525);
FORCEPROP 2 LAST SIG_NAME FM_CPU0_CORETYPE2
J 0
(-4075 3535);
DISPLAY 0.489362 (-4075 3535);
FORCEPROP 2 LASTPROP $XRERR UNIQUE?
J 0
(-4315 3535);
DISPLAY 0.638298 (-4315 3535);
PAINT MONO (-4315 3535);
DISPLAY INVISIBLE (-4315 3535);
WIRE 16 -1 (-3150 3475)(-2375 3475);
FORCEPROP 2 LAST SIG_NAME OCP_SFF_MAIN_PWR_EN
J 0
(-2950 3485);
DISPLAY 0.553191 (-2950 3485);
PAINT WHITE (-2950 3485);
WIRE 16 -1 (-3150 3525)(-2375 3525);
FORCEPROP 2 LAST SIG_NAME CPU0_CORETYPE2
J 0
(-2950 3535);
DISPLAY 0.489362 (-2950 3535);
WIRE 16 -1 (-2375 3875)(-4200 3875);
FORCEPROP 2 LAST SIG_NAME PVDDCR_CPU0_P1_PMALERT
J 0
(-4075 3885);
DISPLAY 0.489362 (-4075 3885);
WIRE 16 -1 (-4200 3475)(-3350 3475);
FORCEPROP 2 LAST SIG_NAME FM_PLD_OCP_SFF_MAIN_PWR_EN_R
J 0
(-4075 3485);
DISPLAY 0.382979 (-4075 3485);
FORCEPROP 2 LASTPROP $XRERR UNIQUE?
J 0
(-4315 3485);
DISPLAY 0.638298 (-4315 3485);
PAINT MONO (-4315 3485);
DISPLAY INVISIBLE (-4315 3485);
WIRE 16 -1 (-3350 3825)(-4200 3825);
FORCEPROP 2 LAST SIG_NAME FM_CLKREQ_M2_1_N
J 0
(-4075 3835);
DISPLAY 0.489362 (-4075 3835);
FORCEPROP 2 LASTPROP $XRERR UNIQUE?
J 0
(-4315 3835);
DISPLAY 0.638298 (-4315 3835);
PAINT MONO (-4315 3835);
DISPLAY INVISIBLE (-4315 3835);
WIRE 16 -1 (-4200 3925)(-3350 3925);
FORCEPROP 2 LAST SIG_NAME FM_PLD_OCP_SFF_AUX_PWR_R_EN
J 0
(-4075 3935);
DISPLAY 0.489362 (-4075 3935);
FORCEPROP 2 LASTPROP $XRERR UNIQUE?
J 0
(-4315 3935);
DISPLAY 0.638298 (-4315 3935);
PAINT MONO (-4315 3935);
DISPLAY INVISIBLE (-4315 3935);
WIRE 16 -1 (-3150 3925)(-2375 3925);
FORCEPROP 2 LAST SIG_NAME FM_PLD_OCP_SFF_AUX_PWR_EN
J 0
(-3035 3935);
DISPLAY 0.553191 (-3035 3935);
PAINT WHITE (-3035 3935);
WIRE 16 -1 (-2375 3825)(-3150 3825);
FORCEPROP 2 LAST SIG_NAME M2_SSD0_CLKREQ_EN_N
J 0
(-2950 3835);
DISPLAY 0.553191 (-2950 3835);
WIRE 16 -1 (-4200 4025)(-2375 4025);
FORCEPROP 2 LAST SIG_NAME M2_0_P3V3_ADC_ALERT
J 0
(-2950 4035);
DISPLAY 0.553191 (-2950 4035);
PAINT WHITE (-2950 4035);
WIRE 16 -1 (-7250 4325)(-6550 4325);
FORCEPROP 2 LAST SIG_NAME CPU0_CORETYPE1
J 0
(-7175 4335);
DISPLAY 0.489362 (-7175 4335);
WIRE 16 -1 (-7250 4025)(-5500 4025);
FORCEPROP 2 LAST SIG_NAME PVDD11_S3_P0_PMALERT
J 0
(-7175 4035);
DISPLAY 0.489362 (-7175 4035);
WIRE 16 -1 (-5500 3975)(-7250 3975);
FORCEPROP 2 LAST SIG_NAME P12V_SCM_ADC_ALERT
J 0
(-7175 3985);
DISPLAY 0.510638 (-7175 3985);
PAINT WHITE (-7175 3985);
WIRE 16 -1 (-6425 3775)(-7275 3775);
FORCEPROP 2 LAST SIG_NAME FM_SEC_MUX_SEL
J 0
(-7160 3785);
DISPLAY 0.489362 (-7160 3785);
WIRE 16 -1 (-6425 3825)(-7275 3825);
FORCEPROP 2 LAST SIG_NAME FM_SEC_MUX_OE_N
J 0
(-7160 3835);
DISPLAY 0.489362 (-7160 3835);
WIRE 16 -1 (-5500 3875)(-6250 3875);
FORCEPROP 2 LAST SIG_NAME E1S_0_P3V3_P12V_ADC_ALERT
J 0
(-6110 3885);
DISPLAY 0.404255 (-6110 3885);
PAINT WHITE (-6110 3885);
FORCEPROP 2 LASTPROP $XRERR UNIQUE?
J 0
(-6350 3885);
DISPLAY 0.638298 (-6350 3885);
PAINT MONO (-6350 3885);
DISPLAY INVISIBLE (-6350 3885);
WIRE 16 -1 (-5500 3925)(-7250 3925);
FORCEPROP 2 LAST SIG_NAME P12V_HSC_T_CRIT_R_N
J 0
(-7175 3935);
DISPLAY 0.489362 (-7175 3935);
WIRE 16 -1 (-6450 3875)(-7250 3875);
FORCEPROP 2 LAST SIG_NAME E1S_0_P3V3_P12V_ADC_R_ALERT
J 0
(-7210 3885);
DISPLAY 0.553191 (-7210 3885);
WIRE 16 -1 (-7250 3725)(-5500 3725);
FORCEPROP 2 LAST SIG_NAME PVDDCR_CPU1_P1_SMB_ALERT
J 0
(-7175 3735);
DISPLAY 0.489362 (-7175 3735);
WIRE 16 -1 (-7250 3625)(-5500 3625);
FORCEPROP 2 LAST SIG_NAME LED_HDD_ACTIVITY_B_PLD_N
J 0
(-7175 3635);
DISPLAY 0.510638 (-7175 3635);
PAINT WHITE (-7175 3635);
WIRE 16 -1 (-7250 3675)(-5500 3675);
FORCEPROP 2 LAST SIG_NAME PVDDCR_CPU1_P0_SMB_ALERT
J 0
(-7175 3685);
DISPLAY 0.489362 (-7175 3685);
WIRE 16 -1 (-5500 4275)(-7250 4275);
FORCEPROP 2 LAST SIG_NAME P12V_HSC_TEMP_ALERT_R_N
J 0
(-7100 4285);
DISPLAY 0.446809 (-7100 4285);
WIRE 16 -1 (-5500 3775)(-6225 3775);
FORCEPROP 2 LAST SIG_NAME FM_SEC_MUX_R_SEL
J 0
(-6035 3785);
DISPLAY 0.489362 (-6035 3785);
FORCEPROP 2 LASTPROP $XRERR UNIQUE?
J 0
(-6275 3785);
DISPLAY 0.638298 (-6275 3785);
PAINT MONO (-6275 3785);
DISPLAY INVISIBLE (-6275 3785);
WIRE 16 -1 (-5500 3825)(-6225 3825);
FORCEPROP 2 LAST SIG_NAME FM_SEC_MUX_OE_R_N
J 0
(-6035 3835);
DISPLAY 0.489362 (-6035 3835);
FORCEPROP 2 LASTPROP $XRERR UNIQUE?
J 0
(-6275 3835);
DISPLAY 0.638298 (-6275 3835);
PAINT MONO (-6275 3835);
DISPLAY INVISIBLE (-6275 3835);
WIRE 16 -1 (-5500 3575)(-7250 3575);
FORCEPROP 2 LAST SIG_NAME FM_SCM_PRSNT1_N
J 0
(-7175 3585);
DISPLAY 0.510638 (-7175 3585);
PAINT WHITE (-7175 3585);
WIRE 16 -1 (-7250 3525)(-5500 3525);
FORCEPROP 2 LAST SIG_NAME FM_THERMAL_ALERT_R_N
J 0
(-7175 3535);
DISPLAY 0.510638 (-7175 3535);
PAINT WHITE (-7175 3535);
WIRE 16 -1 (-7250 3475)(-5500 3475);
FORCEPROP 2 LAST SIG_NAME SMB_BMC_GPU_EN
J 0
(-7175 3485);
DISPLAY 0.510638 (-7175 3485);
PAINT WHITE (-7175 3485);
WIRE 16 -1 (-4200 4425)(-3300 4425);
FORCEPROP 0 LAST SIG_NAME E1S_0_PRSNT_R_N
J 0
(-4075 4435);
DISPLAY 0.489362 (-4075 4435);
FORCEPROP 2 LASTPROP $XRERR UNIQUE?
J 0
(-4315 4435);
DISPLAY 0.638298 (-4315 4435);
PAINT MONO (-4315 4435);
DISPLAY INVISIBLE (-4315 4435);
WIRE 16 -1 (-2375 4475)(-4200 4475);
FORCEPROP 2 LAST SIG_NAME PWRGD_P5V_AUX_R3
J 0
(-4075 4485);
DISPLAY 0.553191 (-4075 4485);
PAINT WHITE (-4075 4485);
WIRE 16 -1 (-4200 4525)(-2375 4525);
FORCEPROP 2 LAST SIG_NAME PWRGD_CHAF_CPU0_R2
J 0
(-4075 4540);
DISPLAY 0.489362 (-4075 4540);
WIRE 16 -1 (-4200 4575)(-3300 4575);
FORCEPROP 2 LAST SIG_NAME P12V_OCP_V3_1_PWRGD
J 0
(-4075 4590);
DISPLAY 0.489362 (-4075 4590);
FORCEPROP 2 LASTPROP $XRERR UNIQUE?
J 0
(-4315 4590);
DISPLAY 0.638298 (-4315 4590);
PAINT MONO (-4315 4590);
DISPLAY INVISIBLE (-4315 4590);
WIRE 16 -1 (-2375 4975)(-3100 4975);
FORCEPROP 2 LAST SIG_NAME PVDD11_S3_P0_EN
J 0
(-2950 4985);
DISPLAY 0.489362 (-2950 4985);
WIRE 16 -1 (-4200 5375)(-2175 5375);
FORCEPROP 2 LAST SIG_NAME FAB_BMC_REV_ID2
J 0
(-2950 5385);
DISPLAY 0.489362 (-2950 5385);
WIRE 16 -1 (-4200 5025)(-3300 5025);
FORCEPROP 2 LAST SIG_NAME FM_PRSNT_CPU1_R_N
J 0
(-4075 5025);
DISPLAY 0.489362 (-4075 5025);
FORCEPROP 2 LASTPROP $XRERR UNIQUE?
J 0
(-4315 5025);
DISPLAY 0.638298 (-4315 5025);
PAINT MONO (-4315 5025);
DISPLAY INVISIBLE (-4315 5025);
WIRE 16 -1 (-3300 5075)(-4200 5075);
FORCEPROP 2 LAST SIG_NAME FM_PVDDCR_CPU1_P1_R_EN
J 0
(-4075 5080);
DISPLAY 0.489362 (-4075 5080);
FORCEPROP 2 LASTPROP $XRERR UNIQUE?
J 0
(-4315 5080);
DISPLAY 0.638298 (-4315 5080);
PAINT MONO (-4315 5080);
DISPLAY INVISIBLE (-4315 5080);
WIRE 16 -1 (-3100 5025)(-2375 5025);
FORCEPROP 2 LAST SIG_NAME FM_PRSNT_CPU1_N
J 0
(-2950 5035);
DISPLAY 0.489362 (-2950 5035);
WIRE 16 -1 (-3300 4325)(-4200 4325);
FORCEPROP 2 LAST SIG_NAME FM_CPU0_SP5R4
J 0
(-4075 4335);
DISPLAY 0.489362 (-4075 4335);
FORCEPROP 2 LASTPROP $XRERR UNIQUE?
J 0
(-4315 4335);
DISPLAY 0.638298 (-4315 4335);
PAINT MONO (-4315 4335);
DISPLAY INVISIBLE (-4315 4335);
WIRE 16 -1 (-4200 5425)(-2175 5425);
FORCEPROP 2 LAST SIG_NAME FAB_BMC_REV_ID1
J 0
(-2950 5435);
DISPLAY 0.489362 (-2950 5435);
WIRE 16 -1 (-3100 5075)(-2375 5075);
FORCEPROP 2 LAST SIG_NAME FM_PVDDCR_CPU1_P1_EN
J 0
(-2950 5085);
DISPLAY 0.489362 (-2950 5085);
WIRE 16 -1 (-3100 4425)(-2375 4425);
FORCEPROP 0 LAST SIG_NAME E1S_0_PRSNT_N
J 0
(-2950 4435);
DISPLAY 0.489362 (-2950 4435);
WIRE 16 -1 (-5500 5225)(-6350 5225);
FORCEPROP 2 LAST SIG_NAME FM_PVDDCR_CPU1_P0_OCP_N
J 0
(-6175 5235);
DISPLAY 0.489362 (-6175 5235);
FORCEPROP 2 LASTPROP $XRERR UNIQUE?
J 0
(-6415 5235);
DISPLAY 0.638298 (-6415 5235);
PAINT MONO (-6415 5235);
DISPLAY INVISIBLE (-6415 5235);
WIRE 16 -1 (-5500 5175)(-6350 5175);
FORCEPROP 2 LAST SIG_NAME FM_PVDDCR_CPU1_P1_OCP_N
J 0
(-6175 5185);
DISPLAY 0.489362 (-6175 5185);
FORCEPROP 2 LASTPROP $XRERR UNIQUE?
J 0
(-6415 5185);
DISPLAY 0.638298 (-6415 5185);
PAINT MONO (-6415 5185);
DISPLAY INVISIBLE (-6415 5185);
WIRE 16 -1 (-5500 5025)(-6350 5025);
FORCEPROP 2 LAST SIG_NAME FM_PDB_BUF_EN_N
J 0
(-6175 5035);
DISPLAY 0.553191 (-6175 5035);
PAINT WHITE (-6175 5035);
FORCEPROP 2 LASTPROP $XRERR UNIQUE?
J 0
(-6415 5035);
DISPLAY 0.638298 (-6415 5035);
PAINT MONO (-6415 5035);
DISPLAY INVISIBLE (-6415 5035);
WIRE 16 -1 (-7250 5075)(-5500 5075);
FORCEPROP 2 LAST SIG_NAME PWRGD_CHGL_CPU1_R2
J 0
(-7175 5090);
DISPLAY 0.489362 (-7175 5090);
WIRE 16 -1 (-7250 4925)(-6550 4925);
FORCEPROP 2 LAST SIG_NAME CPU1_SP5R3
J 0
(-7175 4935);
DISPLAY 0.489362 (-7175 4935);
WIRE 16 -1 (-7250 4975)(-6550 4975);
FORCEPROP 2 LAST SIG_NAME CPU1_SP5R4
J 0
(-7175 4985);
DISPLAY 0.489362 (-7175 4985);
WIRE 16 -1 (-6350 4975)(-5500 4975);
FORCEPROP 2 LAST SIG_NAME FM_CPU1_SP5R4
J 0
(-6175 4985);
DISPLAY 0.489362 (-6175 4985);
FORCEPROP 2 LASTPROP $XRERR UNIQUE?
J 0
(-6415 4985);
DISPLAY 0.638298 (-6415 4985);
PAINT MONO (-6415 4985);
DISPLAY INVISIBLE (-6415 4985);
WIRE 16 -1 (-6550 5025)(-7250 5025);
FORCEPROP 2 LAST SIG_NAME FM_PDB_BUF_EN_R_N
J 0
(-7175 5035);
DISPLAY 0.553191 (-7175 5035);
PAINT WHITE (-7175 5035);
WIRE 16 -1 (-5500 4825)(-7250 4825);
FORCEPROP 2 LAST SIG_NAME PWRGD_CHAF_CPU1_R2
J 0
(-7175 4840);
DISPLAY 0.489362 (-7175 4840);
WIRE 16 -1 (-6350 4125)(-5500 4125);
FORCEPROP 2 LAST SIG_NAME FM_CPU1_CORETYPE0
J 0
(-6175 4135);
DISPLAY 0.489362 (-6175 4135);
FORCEPROP 2 LASTPROP $XRERR UNIQUE?
J 0
(-6415 4135);
DISPLAY 0.638298 (-6415 4135);
PAINT MONO (-6415 4135);
DISPLAY INVISIBLE (-6415 4135);
WIRE 16 -1 (-5500 4225)(-6350 4225);
FORCEPROP 2 LAST SIG_NAME FM_CPU0_SP5R2
J 0
(-6175 4235);
DISPLAY 0.489362 (-6175 4235);
FORCEPROP 2 LASTPROP $XRERR UNIQUE?
J 0
(-6415 4235);
DISPLAY 0.638298 (-6415 4235);
PAINT MONO (-6415 4235);
DISPLAY INVISIBLE (-6415 4235);
WIRE 16 -1 (-5500 4175)(-6350 4175);
FORCEPROP 2 LAST SIG_NAME FM_CPU0_SP5R1
J 0
(-6175 4185);
DISPLAY 0.489362 (-6175 4185);
FORCEPROP 2 LASTPROP $XRERR UNIQUE?
J 0
(-6415 4185);
DISPLAY 0.638298 (-6415 4185);
PAINT MONO (-6415 4185);
DISPLAY INVISIBLE (-6415 4185);
WIRE 16 -1 (-6350 4475)(-5500 4475);
FORCEPROP 0 LAST SIG_NAME FM_APML_MUX2_OE_R_N
J 0
(-6160 4485);
DISPLAY 0.489362 (-6160 4485);
FORCEPROP 2 LASTPROP $XRERR UNIQUE?
J 0
(-6400 4485);
DISPLAY 0.638298 (-6400 4485);
PAINT MONO (-6400 4485);
DISPLAY INVISIBLE (-6400 4485);
WIRE 16 -1 (-7250 6025)(-6550 6025);
FORCEPROP 2 LAST SIG_NAME CPU1_XTRIG_L6
J 0
(-7175 6035);
DISPLAY 0.489362 (-7175 6035);
WIRE 16 -1 (-6550 6075)(-7250 6075);
FORCEPROP 2 LAST SIG_NAME CPU1_XTRIG_L5
J 0
(-7175 6085);
DISPLAY 0.489362 (-7175 6085);
WIRE 16 -1 (-6550 5975)(-7250 5975);
FORCEPROP 2 LAST SIG_NAME CPU1_SA1
J 0
(-7175 5985);
DISPLAY 0.489362 (-7175 5985);
WIRE 16 -1 (-7250 5825)(-6550 5825);
FORCEPROP 2 LAST SIG_NAME CPU1_XTRIG_L7
J 0
(-7175 5835);
DISPLAY 0.489362 (-7175 5835);
WIRE 16 -1 (-3350 6125)(-4200 6125);
FORCEPROP 2 LAST SIG_NAME FM_PVDDCR_CPU0_P1_OCP_N
J 0
(-4075 6125);
DISPLAY 0.489362 (-4075 6125);
FORCEPROP 2 LASTPROP $XRERR UNIQUE?
J 0
(-4315 6125);
DISPLAY 0.638298 (-4315 6125);
PAINT MONO (-4315 6125);
DISPLAY INVISIBLE (-4315 6125);
WIRE 16 -1 (-3350 6075)(-4200 6075);
FORCEPROP 2 LAST SIG_NAME FM_CPU1_PROCHOT_R_N
J 0
(-4075 6075);
DISPLAY 0.489362 (-4075 6075);
FORCEPROP 2 LASTPROP $XRERR UNIQUE?
J 0
(-4315 6075);
DISPLAY 0.638298 (-4315 6075);
PAINT MONO (-4315 6075);
DISPLAY INVISIBLE (-4315 6075);
WIRE 16 -1 (-3350 5575)(-4200 5575);
FORCEPROP 2 LAST SIG_NAME FM_INT_CPU0_HP_UBM_R_N
J 0
(-4075 5575);
DISPLAY 0.489362 (-4075 5575);
FORCEPROP 2 LASTPROP $XRERR UNIQUE?
J 0
(-4315 5575);
DISPLAY 0.638298 (-4315 5575);
PAINT MONO (-4315 5575);
DISPLAY INVISIBLE (-4315 5575);
WIRE 16 -1 (-3350 5775)(-4200 5775);
FORCEPROP 2 LAST SIG_NAME FM_CPU0_PROCHOT_R_N
J 0
(-4075 5775);
DISPLAY 0.489362 (-4075 5775);
FORCEPROP 2 LASTPROP $XRERR UNIQUE?
J 0
(-4315 5775);
DISPLAY 0.638298 (-4315 5775);
PAINT MONO (-4315 5775);
DISPLAY INVISIBLE (-4315 5775);
WIRE 16 -1 (-4200 5525)(-3350 5525);
FORCEPROP 2 LAST SIG_NAME FM_CPU0_SA1
J 0
(-4075 5525);
DISPLAY 0.489362 (-4075 5525);
FORCEPROP 2 LASTPROP $XRERR UNIQUE?
J 0
(-4315 5525);
DISPLAY 0.638298 (-4315 5525);
PAINT MONO (-4315 5525);
DISPLAY INVISIBLE (-4315 5525);
WIRE 16 -1 (-7250 5925)(-6550 5925);
FORCEPROP 2 LAST SIG_NAME CPU0_XTRIG_L6
J 0
(-7175 5935);
DISPLAY 0.489362 (-7175 5935);
WIRE 16 -1 (-7250 5875)(-6550 5875);
FORCEPROP 2 LAST SIG_NAME IRQ_BMC_SMI_N
J 0
(-7175 5885);
DISPLAY 0.553191 (-7175 5885);
PAINT WHITE (-7175 5885);
WIRE 16 -1 (-3150 5525)(-2200 5525);
FORCEPROP 2 LAST SIG_NAME CPU0_SA1
J 0
(-2950 5535);
DISPLAY 0.489362 (-2950 5535);
WIRE 16 -1 (-6550 4875)(-7250 4875);
FORCEPROP 2 LAST SIG_NAME PWRGD_PVDDCR_CPU1_P0
J 0
(-7175 4885);
DISPLAY 0.489362 (-7175 4885);
WIRE 16 -1 (-5500 6125)(-6350 6125);
FORCEPROP 2 LAST SIG_NAME FM_CPU1_XTRIG_L4
J 0
(-6175 6135);
DISPLAY 0.489362 (-6175 6135);
FORCEPROP 2 LASTPROP $XRERR UNIQUE?
J 0
(-6415 6135);
DISPLAY 0.638298 (-6415 6135);
PAINT MONO (-6415 6135);
DISPLAY INVISIBLE (-6415 6135);
WIRE 16 -1 (-5500 6075)(-6350 6075);
FORCEPROP 2 LAST SIG_NAME FM_CPU1_XTRIG_L5
J 0
(-6175 6085);
DISPLAY 0.489362 (-6175 6085);
FORCEPROP 2 LASTPROP $XRERR UNIQUE?
J 0
(-6415 6085);
DISPLAY 0.638298 (-6415 6085);
PAINT MONO (-6415 6085);
DISPLAY INVISIBLE (-6415 6085);
WIRE 16 -1 (-6350 5925)(-5500 5925);
FORCEPROP 2 LAST SIG_NAME FM_CPU0_XTRIG_L6
J 0
(-6175 5935);
DISPLAY 0.489362 (-6175 5935);
FORCEPROP 2 LASTPROP $XRERR UNIQUE?
J 0
(-6415 5935);
DISPLAY 0.638298 (-6415 5935);
PAINT MONO (-6415 5935);
DISPLAY INVISIBLE (-6415 5935);
WIRE 16 -1 (-6550 4775)(-7250 4775);
FORCEPROP 2 LAST SIG_NAME CPU0_SP5R3
J 0
(-7175 4785);
DISPLAY 0.489362 (-7175 4785);
WIRE 16 -1 (-6550 4475)(-7275 4475);
FORCEPROP 0 LAST SIG_NAME FM_APML_MUX2_OE_N
J 0
(-7185 4485);
DISPLAY 0.489362 (-7185 4485);
WIRE 16 -1 (-6550 4425)(-7275 4425);
FORCEPROP 0 LAST SIG_NAME FM_APML_MUX2_SEL
J 0
(-7185 4435);
DISPLAY 0.489362 (-7185 4435);
WIRE 16 -1 (-5500 4875)(-6350 4875);
FORCEPROP 2 LAST SIG_NAME FM_PWRGD_PVDDCR_CPU1_P0
J 0
(-6175 4895);
DISPLAY 0.489362 (-6175 4895);
FORCEPROP 2 LASTPROP $XRERR UNIQUE?
J 0
(-6415 4895);
DISPLAY 0.638298 (-6415 4895);
PAINT MONO (-6415 4895);
DISPLAY INVISIBLE (-6415 4895);
WIRE 16 -1 (-5500 4775)(-6350 4775);
FORCEPROP 2 LAST SIG_NAME FM_CPU0_SP5R3
J 0
(-6175 4785);
DISPLAY 0.489362 (-6175 4785);
FORCEPROP 2 LASTPROP $XRERR UNIQUE?
J 0
(-6415 4785);
DISPLAY 0.638298 (-6415 4785);
PAINT MONO (-6415 4785);
DISPLAY INVISIBLE (-6415 4785);
WIRE 16 -1 (-6350 4725)(-5500 4725);
FORCEPROP 2 LAST SIG_NAME FM_CPU1_CORETYPE2
J 0
(-6175 4735);
DISPLAY 0.489362 (-6175 4735);
FORCEPROP 2 LASTPROP $XRERR UNIQUE?
J 0
(-6415 4735);
DISPLAY 0.638298 (-6415 4735);
PAINT MONO (-6415 4735);
DISPLAY INVISIBLE (-6415 4735);
WIRE 16 -1 (-5500 4675)(-6350 4675);
FORCEPROP 2 LAST SIG_NAME FM_PVDDCR_CPU1_P0_R_EN
J 0
(-6175 4690);
DISPLAY 0.489362 (-6175 4690);
FORCEPROP 2 LASTPROP $XRERR UNIQUE?
J 0
(-6415 4690);
DISPLAY 0.638298 (-6415 4690);
PAINT MONO (-6415 4690);
DISPLAY INVISIBLE (-6415 4690);
WIRE 16 -1 (-6350 4375)(-5500 4375);
FORCEPROP 2 LAST SIG_NAME FM_CPU1_CORETYPE1
J 0
(-6175 4385);
DISPLAY 0.489362 (-6175 4385);
FORCEPROP 2 LASTPROP $XRERR UNIQUE?
J 0
(-6415 4385);
DISPLAY 0.638298 (-6415 4385);
PAINT MONO (-6415 4385);
DISPLAY INVISIBLE (-6415 4385);
WIRE 16 -1 (-6350 4325)(-5500 4325);
FORCEPROP 2 LAST SIG_NAME FM_CPU0_CORETYPE1
J 0
(-6175 4335);
DISPLAY 0.489362 (-6175 4335);
FORCEPROP 2 LASTPROP $XRERR UNIQUE?
J 0
(-6415 4335);
DISPLAY 0.638298 (-6415 4335);
PAINT MONO (-6415 4335);
DISPLAY INVISIBLE (-6415 4335);
WIRE 16 -1 (-6350 4425)(-5500 4425);
FORCEPROP 0 LAST SIG_NAME FM_APML_MUX2_SEL_R
J 0
(-6160 4435);
DISPLAY 0.489362 (-6160 4435);
FORCEPROP 2 LASTPROP $XRERR UNIQUE?
J 0
(-6400 4435);
DISPLAY 0.638298 (-6400 4435);
PAINT MONO (-6400 4435);
DISPLAY INVISIBLE (-6400 4435);
WIRE 16 -1 (-6350 4525)(-5500 4525);
FORCEPROP 2 LAST SIG_NAME FM_CPU1_SP5R1
J 0
(-6175 4535);
DISPLAY 0.489362 (-6175 4535);
FORCEPROP 2 LASTPROP $XRERR UNIQUE?
J 0
(-6415 4535);
DISPLAY 0.638298 (-6415 4535);
PAINT MONO (-6415 4535);
DISPLAY INVISIBLE (-6415 4535);
WIRE 16 -1 (-6350 4575)(-5500 4575);
FORCEPROP 2 LAST SIG_NAME FM_CPU1_SP5R2
J 0
(-6175 4585);
DISPLAY 0.489362 (-6175 4585);
FORCEPROP 2 LASTPROP $XRERR UNIQUE?
J 0
(-6415 4585);
DISPLAY 0.638298 (-6415 4585);
PAINT MONO (-6415 4585);
DISPLAY INVISIBLE (-6415 4585);
WIRE 16 -1 (-6350 5525)(-5500 5525);
FORCEPROP 2 LAST SIG_NAME FM_SMM_CRASHDUMP_R
J 0
(-6175 5535);
DISPLAY 0.553191 (-6175 5535);
PAINT WHITE (-6175 5535);
FORCEPROP 2 LASTPROP $XRERR UNIQUE?
J 0
(-6415 5535);
DISPLAY 0.638298 (-6415 5535);
PAINT MONO (-6415 5535);
DISPLAY INVISIBLE (-6415 5535);
WIRE 16 -1 (-6350 5325)(-5500 5325);
FORCEPROP 2 LAST SIG_NAME FM_BMC_TPM_PRES_N_R
J 0
(-6175 5335);
DISPLAY 0.553191 (-6175 5335);
PAINT WHITE (-6175 5335);
FORCEPROP 2 LASTPROP $XRERR UNIQUE?
J 0
(-6415 5335);
DISPLAY 0.638298 (-6415 5335);
PAINT MONO (-6415 5335);
DISPLAY INVISIBLE (-6415 5335);
WIRE 16 -1 (-5500 5275)(-6350 5275);
FORCEPROP 2 LAST SIG_NAME FM_PVDDCR_CPU0_P0_OCP_N
J 0
(-6175 5285);
DISPLAY 0.489362 (-6175 5285);
FORCEPROP 2 LASTPROP $XRERR UNIQUE?
J 0
(-6415 5285);
DISPLAY 0.638298 (-6415 5285);
PAINT MONO (-6415 5285);
DISPLAY INVISIBLE (-6415 5285);
WIRE 16 -1 (-6350 5875)(-5500 5875);
FORCEPROP 2 LAST SIG_NAME IRQ_BMC_SMI_R_N
J 0
(-6175 5885);
DISPLAY 0.553191 (-6175 5885);
PAINT WHITE (-6175 5885);
FORCEPROP 2 LASTPROP $XRERR UNIQUE?
J 0
(-6415 5885);
DISPLAY 0.638298 (-6415 5885);
PAINT MONO (-6415 5885);
DISPLAY INVISIBLE (-6415 5885);
WIRE 16 -1 (-5500 5975)(-6350 5975);
FORCEPROP 2 LAST SIG_NAME FM_CPU1_SA1
J 0
(-6175 5985);
DISPLAY 0.489362 (-6175 5985);
FORCEPROP 2 LASTPROP $XRERR UNIQUE?
J 0
(-6415 5985);
DISPLAY 0.638298 (-6415 5985);
PAINT MONO (-6415 5985);
DISPLAY INVISIBLE (-6415 5985);
WIRE 16 -1 (-6350 6025)(-5500 6025);
FORCEPROP 2 LAST SIG_NAME FM_CPU1_XTRIG_L6
J 0
(-6175 6035);
DISPLAY 0.489362 (-6175 6035);
FORCEPROP 2 LASTPROP $XRERR UNIQUE?
J 0
(-6415 6035);
DISPLAY 0.638298 (-6415 6035);
PAINT MONO (-6415 6035);
DISPLAY INVISIBLE (-6415 6035);
WIRE 16 -1 (-6550 6125)(-7250 6125);
FORCEPROP 2 LAST SIG_NAME CPU1_XTRIG_L4
J 0
(-7175 6135);
DISPLAY 0.489362 (-7175 6135);
WIRE 16 -1 (-6350 4925)(-5500 4925);
FORCEPROP 2 LAST SIG_NAME FM_CPU1_SP5R3
J 0
(-6175 4935);
DISPLAY 0.489362 (-6175 4935);
FORCEPROP 2 LASTPROP $XRERR UNIQUE?
J 0
(-6415 4935);
DISPLAY 0.638298 (-6415 4935);
PAINT MONO (-6415 4935);
DISPLAY INVISIBLE (-6415 4935);
WIRE 16 -1 (-4200 5475)(-2175 5475);
FORCEPROP 2 LAST SIG_NAME FAB_BMC_REV_ID0
J 0
(-2950 5485);
DISPLAY 0.489362 (-2950 5485);
WIRE 16 -1 (-4200 5725)(-3350 5725);
FORCEPROP 2 LAST SIG_NAME FM_CPU0_SA0
J 0
(-4075 5725);
DISPLAY 0.489362 (-4075 5725);
FORCEPROP 2 LASTPROP $XRERR UNIQUE?
J 0
(-4315 5725);
DISPLAY 0.638298 (-4315 5725);
PAINT MONO (-4315 5725);
DISPLAY INVISIBLE (-4315 5725);
WIRE 16 -1 (-3350 5975)(-4200 5975);
FORCEPROP 2 LAST SIG_NAME FM_PVDD11_S3_P0_OCP_N
J 0
(-4075 5975);
DISPLAY 0.489362 (-4075 5975);
FORCEPROP 2 LASTPROP $XRERR UNIQUE?
J 0
(-4315 5975);
DISPLAY 0.638298 (-4315 5975);
PAINT MONO (-4315 5975);
DISPLAY INVISIBLE (-4315 5975);
WIRE 16 -1 (-3350 6025)(-4200 6025);
FORCEPROP 2 LAST SIG_NAME FM_PVDD11_S3_P1_OCP_N
J 0
(-4075 6025);
DISPLAY 0.489362 (-4075 6025);
FORCEPROP 2 LASTPROP $XRERR UNIQUE?
J 0
(-4315 6025);
DISPLAY 0.638298 (-4315 6025);
PAINT MONO (-4315 6025);
DISPLAY INVISIBLE (-4315 6025);
WIRE 16 -1 (-4200 5825)(-3350 5825);
FORCEPROP 2 LAST SIG_NAME FM_CPU1_SA0
J 0
(-4075 5825);
DISPLAY 0.489362 (-4075 5825);
FORCEPROP 2 LASTPROP $XRERR UNIQUE?
J 0
(-4315 5825);
DISPLAY 0.638298 (-4315 5825);
PAINT MONO (-4315 5825);
DISPLAY INVISIBLE (-4315 5825);
WIRE 16 -1 (-2200 5575)(-3150 5575);
FORCEPROP 2 LAST SIG_NAME FM_INT_CPU0_HP_UBM_N
J 0
(-2950 5585);
DISPLAY 0.489362 (-2950 5585);
WIRE 16 -1 (-2200 6125)(-3150 6125);
FORCEPROP 2 LAST SIG_NAME PVDDCR_CPU0_P1_OCP_N
J 0
(-2950 6135);
DISPLAY 0.489362 (-2950 6135);
WIRE 16 -1 (-2200 6075)(-3150 6075);
FORCEPROP 2 LAST SIG_NAME CPU1_PROCHOT_N
J 0
(-2950 6085);
DISPLAY 0.489362 (-2950 6085);
WIRE 16 -1 (-2200 6025)(-3150 6025);
FORCEPROP 2 LAST SIG_NAME PVDD11_S3_P1_OCP_N
J 0
(-2950 6035);
DISPLAY 0.489362 (-2950 6035);
WIRE 16 -1 (-2200 5975)(-3150 5975);
FORCEPROP 2 LAST SIG_NAME PVDD11_S3_P0_OCP_N
J 0
(-2950 5985);
DISPLAY 0.489362 (-2950 5985);
WIRE 16 -1 (-4200 5925)(-2200 5925);
FORCEPROP 2 LAST SIG_NAME CPU0_THERMTRIP_R_N
J 0
(-2950 5935);
DISPLAY 0.489362 (-2950 5935);
WIRE 16 -1 (-4200 5675)(-2200 5675);
FORCEPROP 2 LAST SIG_NAME CPU1_THERMTRIP_R_N
J 0
(-4075 5675);
DISPLAY 0.489362 (-4075 5675);
WIRE 16 -1 (-3150 5725)(-2200 5725);
FORCEPROP 2 LAST SIG_NAME CPU0_SA0
J 0
(-2950 5735);
DISPLAY 0.489362 (-2950 5735);
WIRE 16 -1 (-2200 5775)(-3150 5775);
FORCEPROP 2 LAST SIG_NAME CPU0_PROCHOT_N
J 0
(-2950 5785);
DISPLAY 0.489362 (-2950 5785);
WIRE 16 -1 (-3150 5825)(-2200 5825);
FORCEPROP 2 LAST SIG_NAME CPU1_SA0
J 0
(-2950 5835);
DISPLAY 0.489362 (-2950 5835);
WIRE 16 -1 (-4200 5625)(-2200 5625);
FORCEPROP 2 LAST SIG_NAME RT_BOARD_ID_ID0
J 0
(-2950 5635);
DISPLAY 0.489362 (-2950 5635);
WIRE 16 -1 (-4200 5875)(-2200 5875);
FORCEPROP 2 LAST SIG_NAME RT_BOARD_ID_ID1
J 0
(-2950 5885);
DISPLAY 0.489362 (-2950 5885);
WIRE 16 -1 (-3100 4375)(-2375 4375);
FORCEPROP 2 LAST SIG_NAME FM_PRSNT_CPU0_N
J 0
(-2950 4385);
DISPLAY 0.489362 (-2950 4385);
WIRE 16 -1 (-3100 4325)(-2375 4325);
FORCEPROP 2 LAST SIG_NAME CPU0_SP5R4
J 0
(-2950 4335);
DISPLAY 0.489362 (-2950 4335);
WIRE 16 -1 (-4200 4775)(-3325 4775);
FORCEPROP 2 LAST SIG_NAME OCP_SFF_P3V3_P12V_ADC_ALERT
J 0
(-4085 4785);
DISPLAY 0.553191 (-4085 4785);
PAINT WHITE (-4085 4785);
FORCEPROP 2 LASTPROP $XRERR UNIQUE?
J 0
(-4325 4785);
DISPLAY 0.638298 (-4325 4785);
PAINT MONO (-4325 4785);
DISPLAY INVISIBLE (-4325 4785);
WIRE 16 -1 (-2375 4825)(-4200 4825);
FORCEPROP 2 LAST SIG_NAME PVDDCR_SOC_P0_EN
J 0
(-4075 4845);
DISPLAY 0.489362 (-4075 4845);
WIRE 16 -1 (-3100 4575)(-2375 4575);
FORCEPROP 2 LAST SIG_NAME P12V_OCP_V3_1_PLD_PWRGD
J 0
(-2950 4585);
DISPLAY 0.446809 (-2950 4585);
WIRE 16 -1 (-4200 4625)(-2375 4625);
FORCEPROP 2 LAST SIG_NAME FM_LED_PWRGD_PVDDCR_SOC_P0
J 0
(-2950 4635);
DISPLAY 0.446809 (-2950 4635);
WIRE 16 -1 (-4200 4675)(-2375 4675);
FORCEPROP 2 LAST SIG_NAME FM_LED_PWRGD_PVDDCR_CPU0_P0
J 0
(-2950 4685);
DISPLAY 0.446809 (-2950 4685);
WIRE 16 -1 (-4200 4725)(-2375 4725);
FORCEPROP 2 LAST SIG_NAME PWRGD_CHGL_CPU0_R2
J 0
(-4075 4740);
DISPLAY 0.489362 (-4075 4740);
WIRE 16 -1 (-3125 4775)(-2400 4775);
FORCEPROP 2 LAST SIG_NAME OCP_SFF_P3V3_P12V_ADC_R_ALERT
J 0
(-2985 4785);
DISPLAY 0.446809 (-2985 4785);
WIRE 16 -1 (-2375 4875)(-4200 4875);
FORCEPROP 2 LAST SIG_NAME PWRGD_PVDDCR_SOC_P0
J 0
(-4075 4890);
DISPLAY 0.489362 (-4075 4890);
WIRE 16 -1 (-4200 4925)(-2375 4925);
FORCEPROP 2 LAST SIG_NAME PWRGD_PVDDCR_CPU0_P0
J 0
(-4075 4935);
DISPLAY 0.489362 (-4075 4935);
WIRE 16 -1 (-3300 4975)(-4200 4975);
FORCEPROP 2 LAST SIG_NAME FM_PVDD11_S3_P0_EN
J 0
(-4075 4980);
DISPLAY 0.489362 (-4075 4980);
FORCEPROP 2 LASTPROP $XRERR UNIQUE?
J 0
(-4315 4980);
DISPLAY 0.638298 (-4315 4980);
PAINT MONO (-4315 4980);
DISPLAY INVISIBLE (-4315 4980);
DOT 1 (-3175 2375);
DOT 1 (-3175 2225);
DOT 1 (-1550 1425);
DOT 1 (-1550 1675);
DOT 1 (-1550 1475);
DOT 1 (-1550 1525);
DOT 1 (-1550 1575);
DOT 1 (-1550 1625);
DOT 1 (-1550 1725);
DOT 1 (-1550 1775);
DOT 1 (-1575 1075);
DOT 1 (-1575 1025);
DOT 1 (-1575 975);
DOT 1 (-1575 925);
DOT 1 (-1575 875);
DOT 1 (-1575 825);
DOT 1 (-1575 775);
DOT 1 (-1575 725);
DOT 1 (-3175 2425);
DOT 1 (-3175 2475);
DOT 1 (-3175 2325);
DOT 1 (-3175 2275);
DOT 1 (-3175 2175);
DOT 1 (-3175 2125);
DOT 1 (-3175 2075);
DOT 1 (-3175 2025);
DOT 1 (-3175 1975);
DOT 1 (-3375 1775);
DOT 1 (-3375 1725);
DOT 1 (-3675 1575);
DOT 1 (-3675 1525);
DOT 1 (-3675 1275);
DOT 1 (-3675 1475);
DOT 1 (-3675 1175);
DOT 1 (-3675 1225);
DOT 1 (-3675 1075);
DOT 1 (-3675 1025);
DOT 1 (-3675 975);
DOT 1 (-3675 875);
DOT 1 (-3675 925);
DOT 1 (-3675 825);
DOT 1 (-3675 775);
DOT 1 (-3675 725);
DOT 1 (-6200 2850);
DOT 1 (-6200 2800);
DOT 1 (-6200 2750);
DOT 1 (-6200 2700);
DOT 1 (-6200 2650);
DOT 1 (-6200 2600);
DOT 1 (-6200 2550);
DOT 1 (-6200 2500);
DOT 1 (-6200 2450);
DOT 1 (-6200 2400);
DOT 1 (-6200 2350);
DOT 1 (-6200 2300);
DOT 1 (-6200 2250);
DOT 1 (-6200 2200);
DOT 1 (-6200 2150);
DOT 1 (-6200 2100);
DOT 1 (-6200 2050);
DOT 1 (-6200 2000);
DOT 1 (-6200 1950);
DOT 1 (-6200 1900);
DOT 1 (-6200 1850);
DOT 1 (-6200 1800);
DOT 1 (-6200 1750);
DOT 1 (-6200 1700);
DOT 1 (-6200 1650);
DOT 1 (-6200 1600);
DOT 1 (-6200 1550);
DOT 1 (-6200 1500);
DOT 1 (-6200 1400);
DOT 1 (-6200 1450);
DOT 1 (-6200 1350);
DOT 1 (-6200 1300);
DOT 1 (-6200 1250);
DOT 1 (-6200 1200);
DOT 1 (-6200 1150);
DOT 1 (-6200 1100);
DOT 1 (-6200 1050);
DOT 1 (-6200 1000);
DOT 1 (-6200 950);
DOT 1 (-6200 900);
DOT 1 (-6200 850);
DOT 1 (-6200 750);
DOT 1 (-6200 800);
DOT 1 (-6200 700);
DOT 1 (-6200 650);
DOT 1 (-6200 600);
DOT 1 (-6200 500);
DOT 1 (-6200 550);
DOT 1 (-6200 450);
DOT 1 (-6200 400);
DOT 1 (-6200 350);
CIRCLE (-6475 3600)(-6385 3600);
PAINT YELLOW (-6475 3600);
CIRCLE (-6675 3800)(-6585 3800);
PAINT YELLOW (-6675 3800);
FORCENOTE
BANK4 P3V3_AUX
(-4025 4100) 0;
DISPLAY LEFT (-4025 4100);
DISPLAY 3.148936 (-4025 4100);
FORCENOTE
TBC
(-6550 3575) 0;
DISPLAY LEFT (-6550 3575);
DISPLAY 1.021277 (-6550 3575);
FORCENOTE
BANK5 P1V8_AUX
(-4100 6275) 0;
DISPLAY LEFT (-4100 6275);
DISPLAY 3.148936 (-4100 6275);
FORCENOTE
BANK3 P3V3_AUX
(-4025 5150) 0;
DISPLAY LEFT (-4025 5150);
DISPLAY 3.148936 (-4025 5150);
FORCENOTE
TBC
(-6750 3775) 0;
DISPLAY LEFT (-6750 3775);
DISPLAY 1.021277 (-6750 3775);
QUIT
